FILE_TYPE = MACRO_DRAWING;
SET COLOR_WIRE YELLOW;
SET COLOR_PROP MONO;
SET COLOR_DOT WHITE;
SET COLOR_ARC YELLOW;
SET COLOR_BODY GREEN;
SET COLOR_NOTE MONO;
SET PROP_DISPLAY VALUE;
SET PAGE_NUMBER P227;
FORCEADD PVDDQ_KLM..1
(4025 1950);
FORCEPROP 3 LASTPIN (4025 1900) SIG_NAME PVDDQ_KLM\g
J 0
(4035 1910);
DISPLAY 0.659574 (4035 1910);
PAINT MONO (4035 1910);
DISPLAY INVISIBLE (4035 1910);
FORCEPROP 2 LAST CDS_LIB mstr_symbols
J 0
(4025 1950);
PAINT ORANGE (4025 1950);
DISPLAY INVISIBLE (4025 1950);
FORCEPROP 1 LAST PATH I1
J 0
(4075 1975);
DISPLAY 0.872340 (4075 1975);
PAINT AQUA (4075 1975);
DISPLAY INVISIBLE (4075 1975);
FORCEPROP 1 LAST VOLTAGE 1.2V
J 0
(3980 1907);
DISPLAY 0.340426 (3980 1907);
PAINT SKYBLUE (3980 1907);
DISPLAY INVISIBLE (3980 1907);
FORCEPROP 1 LAST BODY_TYPE PLUMBING
J 0
(3980 1907);
DISPLAY 0.340426 (3980 1907);
PAINT GREEN (3980 1907);
DISPLAY INVISIBLE (3980 1907);
FORCEPROP 1 LAST HDL_POWER PVDDQ_KLM
J 1
(4025 2000);
DISPLAY 0.872340 (4025 2000);
PAINT GREEN (4025 2000);
DISPLAY INVISIBLE (4025 2000);
FORCEADD IR354XX..1
(1500 2150);
FORCEPROP 2 LASTPIN (1000 1950) $PN 39
J 2
(990 1960);
DISPLAY 0.617021 (990 1960);
PAINT ORANGE (990 1960);
FORCEPROP 1 LAST PART_NUMBER H73688-001
J 0
(1100 1450);
DISPLAY 0.617021 (1100 1450);
PAINT BLUE (1100 1450);
FORCEPROP 2 LASTPIN (2000 1700) $PN 40
J 0
(2010 1710);
DISPLAY 0.617021 (2010 1710);
PAINT ORANGE (2010 1710);
FORCEPROP 2 LASTPIN (2000 1750) $PN 2
J 0
(2010 1760);
DISPLAY 0.617021 (2010 1760);
PAINT ORANGE (2010 1760);
FORCEPROP 2 LASTPIN (1000 1800) $PN 32
J 2
(990 1810);
DISPLAY 0.617021 (990 1810);
PAINT ORANGE (990 1810);
FORCEPROP 1 LAST VALUE IR35411
J 1
(1500 2775);
DISPLAY 0.617021 (1500 2775);
PAINT SKYBLUE (1500 2775);
FORCEPROP 2 LASTPIN (2000 2200) $PN 36
J 0
(2010 2210);
DISPLAY 0.617021 (2010 2210);
PAINT ORANGE (2010 2210);
FORCEPROP 2 LASTPIN (2000 1850) $PN 10
J 0
(2010 1860);
DISPLAY 0.617021 (2010 1860);
PAINT ORANGE (2010 1860);
FORCEPROP 2 LASTPIN (2000 2500) $PN 37
J 0
(2010 2510);
DISPLAY 0.617021 (2010 2510);
PAINT ORANGE (2010 2510);
FORCEPROP 2 LASTPIN (2000 2450) $PN 31
J 0
(2010 2460);
DISPLAY 0.617021 (2010 2460);
PAINT ORANGE (2010 2460);
FORCEPROP 2 LASTPIN (2000 2700) $PN 38
J 0
(2010 2710);
DISPLAY 0.617021 (2010 2710);
PAINT ORANGE (2010 2710);
FORCEPROP 1 LAST LOCATION EU1A2
J 0
(1050 2950);
DISPLAY 0.617021 (1050 2950);
PAINT AQUA (1050 2950);
FORCEPROP 1 LAST MATERIAL IC
J 0
(1050 2900);
DISPLAY 0.617021 (1050 2900);
PAINT SKYBLUE (1050 2900);
FORCEPROP 2 LAST NO_XNET_CONNECTION 1
J 0
(1050 3000);
PAINT MONO (1050 3000);
FORCEPROP 2 LASTPIN (1000 2700) $PN 3
J 2
(990 2710);
DISPLAY 0.617021 (990 2710);
PAINT ORANGE (990 2710);
FORCEPROP 2 LASTPIN (1000 2600) $PN 25
J 2
(990 2610);
DISPLAY 0.617021 (990 2610);
PAINT ORANGE (990 2610);
FORCEPROP 2 LASTPIN (1000 2650) $PN 30
J 2
(990 2660);
DISPLAY 0.617021 (990 2660);
PAINT ORANGE (990 2660);
FORCEPROP 2 LASTPIN (1000 2400) $PN 35
J 2
(990 2410);
DISPLAY 0.617021 (990 2410);
PAINT ORANGE (990 2410);
FORCEPROP 2 LASTPIN (1000 2500) $PN 4
J 2
(990 2510);
DISPLAY 0.617021 (990 2510);
PAINT ORANGE (990 2510);
FORCEPROP 2 LASTPIN (1000 2300) $PN 1
J 2
(990 2310);
DISPLAY 0.617021 (990 2310);
PAINT ORANGE (990 2310);
FORCEPROP 2 LASTPIN (1000 2050) $PN 34
J 2
(990 2060);
DISPLAY 0.617021 (990 2060);
PAINT ORANGE (990 2060);
FORCEPROP 2 LASTPIN (1000 2200) $PN 41
J 2
(990 2210);
DISPLAY 0.617021 (990 2210);
PAINT ORANGE (990 2210);
FORCEPROP 2 LASTPIN (1000 2150) $PN 6
J 2
(990 2160);
DISPLAY 0.617021 (990 2160);
PAINT ORANGE (990 2160);
FORCEPROP 2 LASTPIN (2000 1650) $PN 7
J 0
(2010 1660);
DISPLAY 0.617021 (2010 1660);
PAINT ORANGE (2010 1660);
FORCEPROP 2 LASTPIN (2000 1600) $PN 5
J 0
(2010 1610);
DISPLAY 0.617021 (2010 1610);
PAINT ORANGE (2010 1610);
FORCEPROP 2 LASTPIN (1000 1850) $PN 33
J 2
(990 1860);
DISPLAY 0.617021 (990 1860);
PAINT ORANGE (990 1860);
FORCEPROP 1 LAST PATH I101
J 0
(1500 2900);
PAINT GREEN (1500 2900);
DISPLAY INVISIBLE (1500 2900);
FORCEPROP 2 LAST CDS_LOCATION EU1A2
J 0
(1050 2950);
DISPLAY 0.617021 (1050 2950);
PAINT AQUA (1050 2950);
DISPLAY INVISIBLE (1050 2950);
FORCEPROP 2 LAST SEC 1
J 0
(1050 3000);
DISPLAY 0.680851 (1050 3000);
PAINT MONO (1050 3000);
DISPLAY INVISIBLE (1050 3000);
FORCEPROP 2 LAST SEC_TYPE SM
J 0
(1050 3000);
DISPLAY 1.021277 (1050 3000);
PAINT ORANGE (1050 3000);
DISPLAY INVISIBLE (1050 3000);
FORCEPROP 1 LAST PACK_TYPE SM
J 0
(1050 3000);
PAINT SKYBLUE (1050 3000);
DISPLAY INVISIBLE (1050 3000);
FORCEPROP 2 LAST CDS_LIB mstr_discrete
J 0
(1500 2150);
PAINT ORANGE (1500 2150);
DISPLAY INVISIBLE (1500 2150);
FORCEADD IR354XX..1
(1475 0);
FORCEPROP 2 LASTPIN (1975 50) $PN 36
J 0
(1985 60);
DISPLAY 0.617021 (1985 60);
PAINT ORANGE (1985 60);
FORCEPROP 2 LASTPIN (975 -300) $PN 33
J 2
(965 -290);
DISPLAY 0.617021 (965 -290);
PAINT ORANGE (965 -290);
FORCEPROP 2 LASTPIN (975 -100) $PN 34
J 2
(965 -90);
DISPLAY 0.617021 (965 -90);
PAINT ORANGE (965 -90);
FORCEPROP 2 LASTPIN (975 0) $PN 6
J 2
(965 10);
DISPLAY 0.617021 (965 10);
PAINT ORANGE (965 10);
FORCEPROP 2 LASTPIN (975 150) $PN 1
J 2
(965 160);
DISPLAY 0.617021 (965 160);
PAINT ORANGE (965 160);
FORCEPROP 2 LASTPIN (1975 -550) $PN 5
J 0
(1985 -540);
DISPLAY 0.617021 (1985 -540);
PAINT ORANGE (1985 -540);
FORCEPROP 2 LASTPIN (1975 -450) $PN 40
J 0
(1985 -440);
DISPLAY 0.617021 (1985 -440);
PAINT ORANGE (1985 -440);
FORCEPROP 2 LASTPIN (975 -200) $PN 39
J 2
(965 -190);
DISPLAY 0.617021 (965 -190);
PAINT ORANGE (965 -190);
FORCEPROP 2 LASTPIN (975 -350) $PN 32
J 2
(965 -340);
DISPLAY 0.617021 (965 -340);
PAINT ORANGE (965 -340);
FORCEPROP 2 LASTPIN (1975 -400) $PN 2
J 0
(1985 -390);
DISPLAY 0.617021 (1985 -390);
PAINT ORANGE (1985 -390);
FORCEPROP 2 LASTPIN (1975 -300) $PN 10
J 0
(1985 -290);
DISPLAY 0.617021 (1985 -290);
PAINT ORANGE (1985 -290);
FORCEPROP 2 LASTPIN (975 250) $PN 35
J 2
(965 260);
DISPLAY 0.617021 (965 260);
PAINT ORANGE (965 260);
FORCEPROP 2 LASTPIN (1975 550) $PN 38
J 0
(1985 560);
DISPLAY 0.617021 (1985 560);
PAINT ORANGE (1985 560);
FORCEPROP 2 LASTPIN (1975 300) $PN 31
J 0
(1985 310);
DISPLAY 0.617021 (1985 310);
PAINT ORANGE (1985 310);
FORCEPROP 2 LASTPIN (1975 350) $PN 37
J 0
(1985 360);
DISPLAY 0.617021 (1985 360);
PAINT ORANGE (1985 360);
FORCEPROP 2 LASTPIN (975 550) $PN 3
J 2
(965 560);
DISPLAY 0.617021 (965 560);
PAINT ORANGE (965 560);
FORCEPROP 2 LASTPIN (975 450) $PN 25
J 2
(965 460);
DISPLAY 0.617021 (965 460);
PAINT ORANGE (965 460);
FORCEPROP 2 LASTPIN (975 350) $PN 4
J 2
(965 360);
DISPLAY 0.617021 (965 360);
PAINT ORANGE (965 360);
FORCEPROP 2 LASTPIN (1975 -500) $PN 7
J 0
(1985 -490);
DISPLAY 0.617021 (1985 -490);
PAINT ORANGE (1985 -490);
FORCEPROP 1 LAST VALUE IR35411
J 1
(1475 625);
DISPLAY 0.617021 (1475 625);
PAINT SKYBLUE (1475 625);
FORCEPROP 1 LAST MATERIAL IC
J 0
(1025 750);
DISPLAY 0.617021 (1025 750);
PAINT SKYBLUE (1025 750);
FORCEPROP 1 LAST LOCATION EU1A1
J 0
(1025 800);
DISPLAY 0.617021 (1025 800);
PAINT AQUA (1025 800);
FORCEPROP 2 LAST NO_XNET_CONNECTION 1
J 0
(1025 850);
PAINT MONO (1025 850);
FORCEPROP 2 LASTPIN (975 500) $PN 30
J 2
(965 510);
DISPLAY 0.617021 (965 510);
PAINT ORANGE (965 510);
FORCEPROP 1 LAST PART_NUMBER H73688-001
J 0
(1075 -700);
DISPLAY 0.617021 (1075 -700);
PAINT BLUE (1075 -700);
FORCEPROP 2 LASTPIN (975 50) $PN 41
J 2
(965 60);
DISPLAY 0.617021 (965 60);
PAINT ORANGE (965 60);
FORCEPROP 2 LAST CDS_LIB mstr_discrete
J 0
(1475 0);
PAINT ORANGE (1475 0);
DISPLAY INVISIBLE (1475 0);
FORCEPROP 1 LAST PATH I102
J 0
(1475 750);
PAINT GREEN (1475 750);
DISPLAY INVISIBLE (1475 750);
FORCEPROP 2 LAST CDS_LOCATION EU1A1
J 0
(1025 800);
DISPLAY 0.617021 (1025 800);
PAINT AQUA (1025 800);
DISPLAY INVISIBLE (1025 800);
FORCEPROP 2 LAST SEC 1
J 0
(1025 850);
DISPLAY 0.680851 (1025 850);
PAINT MONO (1025 850);
DISPLAY INVISIBLE (1025 850);
FORCEPROP 2 LAST SEC_TYPE SM
J 0
(1025 850);
DISPLAY 1.021277 (1025 850);
PAINT ORANGE (1025 850);
DISPLAY INVISIBLE (1025 850);
FORCEPROP 1 LAST PACK_TYPE SM
J 0
(1025 850);
PAINT SKYBLUE (1025 850);
DISPLAY INVISIBLE (1025 850);
FORCEADD RES..2
(4325 2325);
FORCEPROP 1 LAST PART_NUMBER G21796-187
J 0
(4365 2200);
DISPLAY 0.617021 (4365 2200);
PAINT BLUE (4365 2200);
FORCEPROP 1 LAST VALUE 68.1K
J 0
(4370 2400);
DISPLAY 0.617021 (4370 2400);
PAINT SKYBLUE (4370 2400);
FORCEPROP 1 LAST LOCATION R1A3
J 0
(4370 2450);
DISPLAY 0.617021 (4370 2450);
PAINT AQUA (4370 2450);
FORCEPROP 1 LAST TOLERANCE 1%
J 0
(4370 2350);
DISPLAY 0.617021 (4370 2350);
PAINT SKYBLUE (4370 2350);
FORCEPROP 1 LAST WATTAGE 1/16W
J 0
(4365 2300);
DISPLAY 0.617021 (4365 2300);
PAINT SKYBLUE (4365 2300);
FORCEPROP 1 LAST MATERIAL EMPTY
J 0
(4365 2250);
DISPLAY 0.617021 (4365 2250);
PAINT RED (4365 2250);
FORCEPROP 1 LAST PACK_TYPE 0402
J 0
(4365 2150);
DISPLAY 0.617021 (4365 2150);
PAINT SKYBLUE (4365 2150);
FORCEPROP 1 LASTPIN (4325 2225) $PN 2
J 0
(4330 2235);
DISPLAY 0.617021 (4330 2235);
PAINT ORANGE (4330 2235);
FORCEPROP 1 LASTPIN (4325 2425) $PN 1
J 0
(4330 2387);
DISPLAY 0.617021 (4330 2387);
PAINT ORANGE (4330 2387);
FORCEPROP 2 LAST SEC_TYPE 0402
J 0
(4375 2550);
DISPLAY 1.021277 (4375 2550);
PAINT ORANGE (4375 2550);
DISPLAY INVISIBLE (4375 2550);
FORCEPROP 2 LAST SEC 1
J 0
(4375 2550);
PAINT MONO (4375 2550);
DISPLAY INVISIBLE (4375 2550);
FORCEPROP 1 LAST PATH I103
J 0
(4375 2500);
DISPLAY 0.978723 (4375 2500);
PAINT WHITE (4375 2500);
DISPLAY INVISIBLE (4375 2500);
FORCEPROP 2 LAST CDS_LIB mstr_discrete
J 0
(4325 2325);
PAINT ORANGE (4325 2325);
DISPLAY INVISIBLE (4325 2325);
FORCEADD GND..1
(4325 2025);
FORCEPROP 3 LASTPIN (4325 2075) SIG_NAME GND\g
J 0
(4335 2085);
DISPLAY 0.659574 (4335 2085);
PAINT MONO (4335 2085);
DISPLAY INVISIBLE (4335 2085);
FORCEPROP 1 LAST VOLTAGE 0
J 0
(4325 2025);
PAINT SKYBLUE (4325 2025);
DISPLAY INVISIBLE (4325 2025);
FORCEPROP 2 LAST CDS_LIB mstr_symbols
J 0
(4325 2025);
PAINT ORANGE (4325 2025);
DISPLAY INVISIBLE (4325 2025);
FORCEPROP 1 LAST PATH I104
J 0
(4400 2025);
DISPLAY 0.872340 (4400 2025);
PAINT AQUA (4400 2025);
DISPLAY INVISIBLE (4400 2025);
FORCEPROP 1 LAST SIZE 1B
J 0
(4400 1975);
DISPLAY 1.723404 (4400 1975);
PAINT GREEN (4400 1975);
DISPLAY INVISIBLE (4400 1975);
FORCEPROP 2 LAST BOM_COST PROC_VRD_VCCIN_CPU0
J 0
(3950 2100);
DISPLAY 1.446809 (3950 2100);
PAINT MONO (3950 2100);
DISPLAY INVISIBLE (3950 2100);
FORCEPROP 2 LAST ROOM PVCCIN_CPU0_PWR_VR
J 0
(3775 2100);
DISPLAY 1.936170 (3775 2100);
PAINT ORANGE (3775 2100);
DISPLAY INVISIBLE (3775 2100);
FORCEPROP 1 LAST BODY_TYPE PLUMBING
J 0
(4280 1982);
DISPLAY 0.340426 (4280 1982);
PAINT GREEN (4280 1982);
DISPLAY INVISIBLE (4280 1982);
FORCEPROP 1 LAST HDL_POWER GND
J 0
(4325 2175);
DISPLAY 1.723404 (4325 2175);
PAINT GREEN (4325 2175);
DISPLAY INVISIBLE (4325 2175);
FORCEADD RES..2
(4300 175);
FORCEPROP 1 LAST MATERIAL EMPTY
J 0
(4340 100);
DISPLAY 0.617021 (4340 100);
PAINT RED (4340 100);
FORCEPROP 1 LAST PART_NUMBER G21796-187
J 0
(4340 50);
DISPLAY 0.617021 (4340 50);
PAINT BLUE (4340 50);
FORCEPROP 1 LASTPIN (4300 75) $PN 2
J 0
(4305 85);
DISPLAY 0.617021 (4305 85);
PAINT ORANGE (4305 85);
FORCEPROP 1 LAST WATTAGE 1/16W
J 0
(4340 150);
DISPLAY 0.617021 (4340 150);
PAINT SKYBLUE (4340 150);
FORCEPROP 1 LAST PACK_TYPE 0402
J 0
(4340 0);
DISPLAY 0.617021 (4340 0);
PAINT SKYBLUE (4340 0);
FORCEPROP 1 LAST TOLERANCE 1%
J 0
(4345 200);
DISPLAY 0.617021 (4345 200);
PAINT SKYBLUE (4345 200);
FORCEPROP 1 LASTPIN (4300 275) $PN 1
J 0
(4305 237);
DISPLAY 0.617021 (4305 237);
PAINT ORANGE (4305 237);
FORCEPROP 1 LAST VALUE 68.1K
J 0
(4345 250);
DISPLAY 0.617021 (4345 250);
PAINT SKYBLUE (4345 250);
FORCEPROP 1 LAST LOCATION R1A2
J 0
(4345 300);
DISPLAY 0.617021 (4345 300);
PAINT AQUA (4345 300);
FORCEPROP 2 LAST CDS_LIB mstr_discrete
J 0
(4300 175);
PAINT ORANGE (4300 175);
DISPLAY INVISIBLE (4300 175);
FORCEPROP 1 LAST PATH I105
J 0
(4350 350);
DISPLAY 0.978723 (4350 350);
PAINT WHITE (4350 350);
DISPLAY INVISIBLE (4350 350);
FORCEPROP 2 LAST SEC 1
J 0
(4350 400);
PAINT MONO (4350 400);
DISPLAY INVISIBLE (4350 400);
FORCEPROP 2 LAST SEC_TYPE 0402
J 0
(4350 400);
DISPLAY 1.021277 (4350 400);
PAINT ORANGE (4350 400);
DISPLAY INVISIBLE (4350 400);
FORCEADD GND..1
(4300 -125);
FORCEPROP 3 LASTPIN (4300 -75) SIG_NAME GND\g
J 0
(4310 -65);
DISPLAY 0.659574 (4310 -65);
PAINT MONO (4310 -65);
DISPLAY INVISIBLE (4310 -65);
FORCEPROP 2 LAST ROOM PVCCIN_CPU0_PWR_VR
J 0
(3750 -50);
DISPLAY 1.936170 (3750 -50);
PAINT ORANGE (3750 -50);
DISPLAY INVISIBLE (3750 -50);
FORCEPROP 2 LAST BOM_COST PROC_VRD_VCCIN_CPU0
J 0
(3925 -50);
DISPLAY 1.446809 (3925 -50);
PAINT MONO (3925 -50);
DISPLAY INVISIBLE (3925 -50);
FORCEPROP 2 LAST CDS_LIB mstr_symbols
J 0
(4300 -125);
PAINT ORANGE (4300 -125);
DISPLAY INVISIBLE (4300 -125);
FORCEPROP 1 LAST VOLTAGE 0
J 0
(4300 -125);
PAINT SKYBLUE (4300 -125);
DISPLAY INVISIBLE (4300 -125);
FORCEPROP 1 LAST PATH I106
J 0
(4375 -125);
DISPLAY 0.872340 (4375 -125);
PAINT AQUA (4375 -125);
DISPLAY INVISIBLE (4375 -125);
FORCEPROP 1 LAST SIZE 1B
J 0
(4375 -175);
DISPLAY 1.723404 (4375 -175);
PAINT GREEN (4375 -175);
DISPLAY INVISIBLE (4375 -175);
FORCEPROP 1 LAST BODY_TYPE PLUMBING
J 0
(4255 -168);
DISPLAY 0.340426 (4255 -168);
PAINT GREEN (4255 -168);
DISPLAY INVISIBLE (4255 -168);
FORCEPROP 1 LAST HDL_POWER GND
J 0
(4300 25);
DISPLAY 1.723404 (4300 25);
PAINT GREEN (4300 25);
DISPLAY INVISIBLE (4300 25);
FORCEADD P5V_STBY..1
(250 3125);
FORCEPROP 3 LASTPIN (250 3075) SIG_NAME P5V_STBY\g
J 0
(260 3085);
DISPLAY 0.659574 (260 3085);
PAINT MONO (260 3085);
DISPLAY INVISIBLE (260 3085);
FORCEPROP 1 LAST VOLTAGE 5.0V
J 0
(205 3082);
DISPLAY 0.340426 (205 3082);
PAINT SKYBLUE (205 3082);
DISPLAY INVISIBLE (205 3082);
FORCEPROP 2 LAST CDS_LIB mstr_symbols
J 0
(250 3125);
PAINT ORANGE (250 3125);
DISPLAY INVISIBLE (250 3125);
FORCEPROP 1 LAST SIZE 1B
J 0
(295 3147);
DISPLAY 0.340426 (295 3147);
PAINT GREEN (295 3147);
DISPLAY INVISIBLE (295 3147);
FORCEPROP 1 LAST PATH I107
J 0
(295 3127);
DISPLAY 0.340426 (295 3127);
PAINT GREEN (295 3127);
DISPLAY INVISIBLE (295 3127);
FORCEPROP 1 LAST BODY_TYPE PLUMBING
J 0
(205 3082);
DISPLAY 0.340426 (205 3082);
PAINT GREEN (205 3082);
DISPLAY INVISIBLE (205 3082);
FORCEPROP 1 LAST HDL_POWER P5V_STBY
J 0
(-50 3000);
DISPLAY 0.872340 (-50 3000);
PAINT ORANGE (-50 3000);
DISPLAY INVISIBLE (-50 3000);
FORCEADD CAP_A..1
(825 1650);
FORCEPROP 1 LAST PACK_TYPE 0402V
J 0
(875 1450);
DISPLAY 0.617021 (875 1450);
PAINT SKYBLUE (875 1450);
FORCEPROP 1 LAST PART_NUMBER A36096-030
J 0
(875 1500);
DISPLAY 0.617021 (875 1500);
PAINT BLUE (875 1500);
FORCEPROP 1 LAST VOLTAGE 16V
J 0
(875 1650);
DISPLAY 0.617021 (875 1650);
PAINT SKYBLUE (875 1650);
FORCEPROP 1 LAST TOLERANCE 10%
J 0
(875 1600);
DISPLAY 0.617021 (875 1600);
PAINT SKYBLUE (875 1600);
FORCEPROP 1 LAST MATERIAL X7R
J 0
(875 1550);
DISPLAY 0.617021 (875 1550);
PAINT SKYBLUE (875 1550);
FORCEPROP 1 LAST LOCATION CT7
J 0
(675 1650);
DISPLAY 0.617021 (675 1650);
PAINT AQUA (675 1650);
FORCEPROP 1 LAST VALUE 0.1UF
J 0
(875 1700);
DISPLAY 0.617021 (875 1700);
PAINT SKYBLUE (875 1700);
FORCEPROP 0 LAST STATUS NOPOP
J 0
(575 1500);
DISPLAY 1.021277 (575 1500);
PAINT ORANGE (575 1500);
FORCEPROP 2 LAST CDS_LIB dev_discrete
J 0
(825 1650);
PAINT MONO (825 1650);
DISPLAY INVISIBLE (825 1650);
FORCEPROP 1 LAST PATH I109
J 0
(875 1800);
DISPLAY 0.978723 (875 1800);
PAINT WHITE (875 1800);
DISPLAY INVISIBLE (875 1800);
FORCEPROP 2 LAST ROOM PVCCIN_CPU0_PWR_VR
J 0
(875 1800);
DISPLAY 1.361702 (875 1800);
PAINT ORANGE (875 1800);
DISPLAY INVISIBLE (875 1800);
FORCEPROP 1 LASTPIN (825 1750) $PN 1
J 0
(835 1730);
DISPLAY 0.787234 (835 1730);
PAINT ORANGE (835 1730);
DISPLAY INVISIBLE (835 1730);
FORCEPROP 1 LASTPIN (825 1550) $PN 2
J 0
(835 1530);
DISPLAY 0.787234 (835 1530);
PAINT ORANGE (835 1530);
DISPLAY INVISIBLE (835 1530);
FORCEADD GND..1
(825 1400);
FORCEPROP 3 LASTPIN (825 1450) SIG_NAME GND\g
J 0
(835 1460);
DISPLAY 0.659574 (835 1460);
PAINT MONO (835 1460);
DISPLAY INVISIBLE (835 1460);
FORCEPROP 2 LAST CDS_LIB mstr_symbols
J 0
(825 1400);
PAINT MONO (825 1400);
DISPLAY INVISIBLE (825 1400);
FORCEPROP 1 LAST PATH I110
J 0
(900 1400);
DISPLAY 0.872340 (900 1400);
PAINT AQUA (900 1400);
DISPLAY INVISIBLE (900 1400);
FORCEPROP 1 LAST VOLTAGE 0
J 0
(825 1400);
PAINT SKYBLUE (825 1400);
DISPLAY INVISIBLE (825 1400);
FORCEPROP 1 LAST SIZE 1B
J 0
(900 1350);
DISPLAY 1.723404 (900 1350);
PAINT GREEN (900 1350);
DISPLAY INVISIBLE (900 1350);
FORCEPROP 2 LAST BOM_COST PROC_VRD_VCCIN_CPU0
J 0
(450 1475);
DISPLAY 1.446809 (450 1475);
PAINT MONO (450 1475);
DISPLAY INVISIBLE (450 1475);
FORCEPROP 2 LAST ROOM PVCCIN_CPU0_PWR_VR
J 0
(275 1475);
DISPLAY 1.936170 (275 1475);
PAINT ORANGE (275 1475);
DISPLAY INVISIBLE (275 1475);
FORCEPROP 1 LAST BODY_TYPE PLUMBING
J 0
(780 1357);
DISPLAY 0.340426 (780 1357);
PAINT GREEN (780 1357);
DISPLAY INVISIBLE (780 1357);
FORCEPROP 1 LAST HDL_POWER GND
J 0
(825 1550);
DISPLAY 1.723404 (825 1550);
PAINT GREEN (825 1550);
DISPLAY INVISIBLE (825 1550);
FORCEADD SC2K2P50V3KX-GP..1
(2600 1700);
FORCEPROP 1 LAST LOCATION CT9
J 0
(2625 1730);
DISPLAY 0.617021 (2625 1730);
PAINT GREEN (2625 1730);
FORCEPROP 0 LAST STATUS NOPOP
J 0
(2650 1600);
DISPLAY 1.021277 (2650 1600);
PAINT ORANGE (2650 1600);
FORCEPROP 1 LAST VALUE SC2K2P50V3KX-GP
J 0
(2625 1650);
DISPLAY 0.617021 (2625 1650);
PAINT GREEN (2625 1650);
FORCEPROP 1 LAST PACK_TYPE SMD-BCG6
J 0
(2600 1700);
DISPLAY 0.617021 (2600 1700);
PAINT GREEN (2600 1700);
DISPLAY INVISIBLE (2600 1700);
FORCEPROP 1 LAST PART_NUMBER 78.22224.2BL
J 0
(2600 1700);
DISPLAY 0.617021 (2600 1700);
PAINT GREEN (2600 1700);
DISPLAY INVISIBLE (2600 1700);
FORCEPROP 1 LAST PATH I111
J 0
(2600 1700);
DISPLAY 0.617021 (2600 1700);
PAINT GREEN (2600 1700);
DISPLAY INVISIBLE (2600 1700);
FORCEPROP 1 LAST CDS_LMAN_SYM_OUTLINE -50,25,50,-25
J 0
(2600 1700);
DISPLAY 0.468085 (2600 1700);
PAINT GREEN (2600 1700);
DISPLAY INVISIBLE (2600 1700);
FORCEPROP 2 LAST CDS_LIB w_hdl
J 0
(2600 1700);
PAINT MONO (2600 1700);
DISPLAY INVISIBLE (2600 1700);
FORCEADD GND..1
(2600 1150);
FORCEPROP 3 LASTPIN (2600 1200) SIG_NAME GND\g
J 0
(2610 1210);
DISPLAY 0.659574 (2610 1210);
PAINT MONO (2610 1210);
DISPLAY INVISIBLE (2610 1210);
FORCEPROP 2 LAST CDS_LIB mstr_symbols
J 0
(2600 1150);
PAINT MONO (2600 1150);
DISPLAY INVISIBLE (2600 1150);
FORCEPROP 1 LAST PATH I113
J 0
(2675 1150);
DISPLAY 0.872340 (2675 1150);
PAINT AQUA (2675 1150);
DISPLAY INVISIBLE (2675 1150);
FORCEPROP 1 LAST SIZE 1B
J 0
(2675 1100);
DISPLAY 1.723404 (2675 1100);
PAINT GREEN (2675 1100);
DISPLAY INVISIBLE (2675 1100);
FORCEPROP 1 LAST VOLTAGE 0
J 0
(2600 1150);
PAINT SKYBLUE (2600 1150);
DISPLAY INVISIBLE (2600 1150);
FORCEPROP 2 LAST BOM_COST PROC_VRD_VCCIN_CPU0
J 0
(2225 1225);
DISPLAY 1.446809 (2225 1225);
PAINT MONO (2225 1225);
DISPLAY INVISIBLE (2225 1225);
FORCEPROP 2 LAST ROOM PVCCIN_CPU0_PWR_VR
J 0
(2050 1225);
DISPLAY 1.936170 (2050 1225);
PAINT ORANGE (2050 1225);
DISPLAY INVISIBLE (2050 1225);
FORCEPROP 1 LAST BODY_TYPE PLUMBING
J 0
(2555 1107);
DISPLAY 0.340426 (2555 1107);
PAINT GREEN (2555 1107);
DISPLAY INVISIBLE (2555 1107);
FORCEPROP 1 LAST HDL_POWER GND
J 0
(2600 1300);
DISPLAY 1.723404 (2600 1300);
PAINT GREEN (2600 1300);
DISPLAY INVISIBLE (2600 1300);
FORCEADD CAP..1
(2725 2125);
FORCEPROP 1 LAST PACK_TYPE 0402LF
J 0
(2775 1925);
DISPLAY 0.617021 (2775 1925);
PAINT SKYBLUE (2775 1925);
FORCEPROP 1 LAST LOCATION CT8
J 0
(2650 2175);
DISPLAY 0.617021 (2650 2175);
PAINT AQUA (2650 2175);
FORCEPROP 1 LAST VALUE 1000PF
J 0
(2775 2175);
DISPLAY 0.617021 (2775 2175);
PAINT SKYBLUE (2775 2175);
FORCEPROP 1 LAST VOLTAGE 50V
J 0
(2775 2125);
DISPLAY 0.617021 (2775 2125);
PAINT SKYBLUE (2775 2125);
FORCEPROP 1 LAST TOLERANCE 10%
J 0
(2775 2075);
DISPLAY 0.617021 (2775 2075);
PAINT SKYBLUE (2775 2075);
FORCEPROP 1 LAST MATERIAL X7R
J 0
(2775 2025);
DISPLAY 0.617021 (2775 2025);
PAINT SKYBLUE (2775 2025);
FORCEPROP 1 LAST PART_NUMBER A36096-046
J 0
(2775 1975);
DISPLAY 0.617021 (2775 1975);
PAINT BLUE (2775 1975);
FORCEPROP 0 LAST STATUS NOPOP
J 0
(2925 2150);
DISPLAY 1.021277 (2925 2150);
PAINT ORANGE (2925 2150);
FORCEPROP 0 LAST ROOM VDDQ_KLM_PWR_VR
J 0
(2775 2325);
DISPLAY 1.021277 (2775 2325);
PAINT ORANGE (2775 2325);
DISPLAY INVISIBLE (2775 2325);
FORCEPROP 1 LAST PATH I114
J 0
(2775 2275);
DISPLAY 0.978723 (2775 2275);
PAINT WHITE (2775 2275);
DISPLAY INVISIBLE (2775 2275);
FORCEPROP 2 LAST CDS_LIB mstr_discrete
J 0
(2725 2125);
PAINT MONO (2725 2125);
DISPLAY INVISIBLE (2725 2125);
FORCEPROP 1 LASTPIN (2725 2025) $PN 2
J 0
(2735 2005);
DISPLAY 0.787234 (2735 2005);
PAINT ORANGE (2735 2005);
DISPLAY INVISIBLE (2735 2005);
FORCEPROP 1 LASTPIN (2725 2225) $PN 1
J 0
(2735 2205);
DISPLAY 0.787234 (2735 2205);
PAINT ORANGE (2735 2205);
DISPLAY INVISIBLE (2735 2205);
FORCEADD GND..1
(2725 1925);
FORCEPROP 3 LASTPIN (2725 1975) SIG_NAME GND\g
J 0
(2735 1985);
DISPLAY 0.659574 (2735 1985);
PAINT MONO (2735 1985);
DISPLAY INVISIBLE (2735 1985);
FORCEPROP 1 LAST SIZE 1B
J 0
(2800 1875);
DISPLAY 1.170213 (2800 1875);
PAINT AQUA (2800 1875);
DISPLAY INVISIBLE (2800 1875);
FORCEPROP 1 LAST VOLTAGE 0
J 0
(2725 1925);
PAINT SKYBLUE (2725 1925);
DISPLAY INVISIBLE (2725 1925);
FORCEPROP 2 LAST ROOM VDDQ_KLM_PWR_VR
J 0
(2150 2000);
DISPLAY 1.361702 (2150 2000);
PAINT ORANGE (2150 2000);
DISPLAY INVISIBLE (2150 2000);
FORCEPROP 1 LAST PATH I115
J 0
(2800 1925);
DISPLAY 0.872340 (2800 1925);
PAINT AQUA (2800 1925);
DISPLAY INVISIBLE (2800 1925);
FORCEPROP 2 LAST CDS_LIB mstr_symbols
J 0
(2725 1925);
PAINT MONO (2725 1925);
DISPLAY INVISIBLE (2725 1925);
FORCEPROP 1 LAST BODY_TYPE PLUMBING
J 0
(2680 1882);
DISPLAY 0.340426 (2680 1882);
PAINT GREEN (2680 1882);
DISPLAY INVISIBLE (2680 1882);
FORCEPROP 1 LAST HDL_POWER GND
J 0
(2725 2075);
DISPLAY 1.170213 (2725 2075);
PAINT GREEN (2725 2075);
DISPLAY INVISIBLE (2725 2075);
FORCEADD SC2K2P50V3KX-GP..1
(2575 -425);
FORCEPROP 1 LAST VALUE SC2K2P50V3KX-GP
J 0
(2600 -475);
DISPLAY 0.617021 (2600 -475);
PAINT GREEN (2600 -475);
FORCEPROP 0 LAST STATUS NOPOP
J 0
(2575 -525);
DISPLAY 1.021277 (2575 -525);
PAINT ORANGE (2575 -525);
FORCEPROP 1 LAST LOCATION CT11
J 0
(2600 -395);
DISPLAY 0.617021 (2600 -395);
PAINT GREEN (2600 -395);
FORCEPROP 2 LAST CDS_LIB w_hdl
J 0
(2575 -425);
PAINT MONO (2575 -425);
DISPLAY INVISIBLE (2575 -425);
FORCEPROP 1 LAST PATH I116
J 0
(2575 -425);
DISPLAY 0.617021 (2575 -425);
PAINT GREEN (2575 -425);
DISPLAY INVISIBLE (2575 -425);
FORCEPROP 1 LAST CDS_LMAN_SYM_OUTLINE -50,25,50,-25
J 0
(2575 -425);
DISPLAY 0.468085 (2575 -425);
PAINT GREEN (2575 -425);
DISPLAY INVISIBLE (2575 -425);
FORCEPROP 1 LAST PACK_TYPE SMD-BCG6
J 0
(2575 -425);
DISPLAY 0.617021 (2575 -425);
PAINT GREEN (2575 -425);
DISPLAY INVISIBLE (2575 -425);
FORCEPROP 1 LAST PART_NUMBER 78.22224.2BL
J 0
(2575 -425);
DISPLAY 0.617021 (2575 -425);
PAINT GREEN (2575 -425);
DISPLAY INVISIBLE (2575 -425);
FORCEADD GND..1
(2575 -975);
FORCEPROP 3 LASTPIN (2575 -925) SIG_NAME GND\g
J 0
(2585 -915);
DISPLAY 0.659574 (2585 -915);
PAINT MONO (2585 -915);
DISPLAY INVISIBLE (2585 -915);
FORCEPROP 1 LAST HDL_POWER GND
J 0
(2575 -825);
DISPLAY 1.723404 (2575 -825);
PAINT GREEN (2575 -825);
DISPLAY INVISIBLE (2575 -825);
FORCEPROP 1 LAST BODY_TYPE PLUMBING
J 0
(2530 -1018);
DISPLAY 0.340426 (2530 -1018);
PAINT GREEN (2530 -1018);
DISPLAY INVISIBLE (2530 -1018);
FORCEPROP 2 LAST ROOM PVCCIN_CPU0_PWR_VR
J 0
(2025 -900);
DISPLAY 1.936170 (2025 -900);
PAINT ORANGE (2025 -900);
DISPLAY INVISIBLE (2025 -900);
FORCEPROP 2 LAST BOM_COST PROC_VRD_VCCIN_CPU0
J 0
(2200 -900);
DISPLAY 1.446809 (2200 -900);
PAINT MONO (2200 -900);
DISPLAY INVISIBLE (2200 -900);
FORCEPROP 1 LAST VOLTAGE 0
J 0
(2575 -975);
PAINT SKYBLUE (2575 -975);
DISPLAY INVISIBLE (2575 -975);
FORCEPROP 1 LAST SIZE 1B
J 0
(2650 -1025);
DISPLAY 1.723404 (2650 -1025);
PAINT GREEN (2650 -1025);
DISPLAY INVISIBLE (2650 -1025);
FORCEPROP 1 LAST PATH I117
J 0
(2650 -975);
DISPLAY 0.872340 (2650 -975);
PAINT AQUA (2650 -975);
DISPLAY INVISIBLE (2650 -975);
FORCEPROP 2 LAST CDS_LIB mstr_symbols
J 0
(2575 -975);
PAINT MONO (2575 -975);
DISPLAY INVISIBLE (2575 -975);
FORCEADD CAP..1
(2600 50);
FORCEPROP 1 LAST VOLTAGE 50V
J 0
(2650 50);
DISPLAY 0.617021 (2650 50);
PAINT SKYBLUE (2650 50);
FORCEPROP 1 LAST LOCATION CT10
J 0
(2450 50);
DISPLAY 0.617021 (2450 50);
PAINT AQUA (2450 50);
FORCEPROP 0 LAST STATUS NOPOP
J 0
(2375 -25);
DISPLAY 1.021277 (2375 -25);
PAINT ORANGE (2375 -25);
FORCEPROP 1 LAST TOLERANCE 10%
J 0
(2650 0);
DISPLAY 0.617021 (2650 0);
PAINT SKYBLUE (2650 0);
FORCEPROP 1 LAST PACK_TYPE 0402LF
J 0
(2650 -150);
DISPLAY 0.617021 (2650 -150);
PAINT SKYBLUE (2650 -150);
FORCEPROP 1 LAST VALUE 1000PF
J 0
(2650 100);
DISPLAY 0.617021 (2650 100);
PAINT SKYBLUE (2650 100);
FORCEPROP 1 LAST MATERIAL X7R
J 0
(2650 -50);
DISPLAY 0.617021 (2650 -50);
PAINT SKYBLUE (2650 -50);
FORCEPROP 1 LAST PART_NUMBER A36096-046
J 0
(2650 -100);
DISPLAY 0.617021 (2650 -100);
PAINT BLUE (2650 -100);
FORCEPROP 2 LAST CDS_LIB mstr_discrete
J 0
(2600 50);
PAINT MONO (2600 50);
DISPLAY INVISIBLE (2600 50);
FORCEPROP 1 LAST PATH I119
J 0
(2650 200);
DISPLAY 0.978723 (2650 200);
PAINT WHITE (2650 200);
DISPLAY INVISIBLE (2650 200);
FORCEPROP 0 LAST ROOM VDDQ_KLM_PWR_VR
J 0
(2650 250);
DISPLAY 1.021277 (2650 250);
PAINT ORANGE (2650 250);
DISPLAY INVISIBLE (2650 250);
FORCEPROP 1 LASTPIN (2600 -50) $PN 2
J 0
(2610 -70);
DISPLAY 0.787234 (2610 -70);
PAINT ORANGE (2610 -70);
DISPLAY INVISIBLE (2610 -70);
FORCEPROP 1 LASTPIN (2600 150) $PN 1
J 0
(2610 130);
DISPLAY 0.787234 (2610 130);
PAINT ORANGE (2610 130);
DISPLAY INVISIBLE (2610 130);
FORCEADD GND..1
(2600 -150);
FORCEPROP 3 LASTPIN (2600 -100) SIG_NAME GND\g
J 0
(2610 -90);
DISPLAY 0.659574 (2610 -90);
PAINT MONO (2610 -90);
DISPLAY INVISIBLE (2610 -90);
FORCEPROP 2 LAST CDS_LIB mstr_symbols
J 0
(2600 -150);
PAINT MONO (2600 -150);
DISPLAY INVISIBLE (2600 -150);
FORCEPROP 1 LAST PATH I120
J 0
(2675 -150);
DISPLAY 0.872340 (2675 -150);
PAINT AQUA (2675 -150);
DISPLAY INVISIBLE (2675 -150);
FORCEPROP 2 LAST ROOM VDDQ_KLM_PWR_VR
J 0
(2025 -75);
DISPLAY 1.361702 (2025 -75);
PAINT ORANGE (2025 -75);
DISPLAY INVISIBLE (2025 -75);
FORCEPROP 1 LAST VOLTAGE 0
J 0
(2600 -150);
PAINT SKYBLUE (2600 -150);
DISPLAY INVISIBLE (2600 -150);
FORCEPROP 1 LAST SIZE 1B
J 0
(2675 -200);
DISPLAY 1.170213 (2675 -200);
PAINT AQUA (2675 -200);
DISPLAY INVISIBLE (2675 -200);
FORCEPROP 1 LAST BODY_TYPE PLUMBING
J 0
(2555 -193);
DISPLAY 0.340426 (2555 -193);
PAINT GREEN (2555 -193);
DISPLAY INVISIBLE (2555 -193);
FORCEPROP 1 LAST HDL_POWER GND
J 0
(2600 0);
DISPLAY 1.170213 (2600 0);
PAINT GREEN (2600 0);
DISPLAY INVISIBLE (2600 0);
FORCEADD CAP_A..1
(800 -500);
FORCEPROP 0 LAST STATUS NOPOP
J 0
(550 -600);
DISPLAY 1.021277 (550 -600);
PAINT ORANGE (550 -600);
FORCEPROP 1 LAST VALUE 0.1UF
J 0
(850 -450);
DISPLAY 0.617021 (850 -450);
PAINT SKYBLUE (850 -450);
FORCEPROP 1 LAST MATERIAL X7R
J 0
(850 -600);
DISPLAY 0.617021 (850 -600);
PAINT SKYBLUE (850 -600);
FORCEPROP 1 LAST TOLERANCE 10%
J 0
(850 -550);
DISPLAY 0.617021 (850 -550);
PAINT SKYBLUE (850 -550);
FORCEPROP 1 LAST VOLTAGE 16V
J 0
(850 -500);
DISPLAY 0.617021 (850 -500);
PAINT SKYBLUE (850 -500);
FORCEPROP 1 LAST LOCATION CT12
J 0
(650 -500);
DISPLAY 0.617021 (650 -500);
PAINT AQUA (650 -500);
FORCEPROP 1 LAST PACK_TYPE 0402V
J 0
(850 -700);
DISPLAY 0.617021 (850 -700);
PAINT SKYBLUE (850 -700);
FORCEPROP 1 LAST PART_NUMBER A36096-030
J 0
(850 -650);
DISPLAY 0.617021 (850 -650);
PAINT BLUE (850 -650);
FORCEPROP 2 LAST CDS_LIB dev_discrete
J 0
(800 -500);
PAINT MONO (800 -500);
DISPLAY INVISIBLE (800 -500);
FORCEPROP 1 LAST PATH I122
J 0
(850 -350);
DISPLAY 0.978723 (850 -350);
PAINT WHITE (850 -350);
DISPLAY INVISIBLE (850 -350);
FORCEPROP 2 LAST ROOM PVCCIN_CPU0_PWR_VR
J 0
(850 -350);
DISPLAY 1.361702 (850 -350);
PAINT ORANGE (850 -350);
DISPLAY INVISIBLE (850 -350);
FORCEPROP 1 LASTPIN (800 -400) $PN 1
J 0
(810 -420);
DISPLAY 0.787234 (810 -420);
PAINT ORANGE (810 -420);
DISPLAY INVISIBLE (810 -420);
FORCEPROP 1 LASTPIN (800 -600) $PN 2
J 0
(810 -620);
DISPLAY 0.787234 (810 -620);
PAINT ORANGE (810 -620);
DISPLAY INVISIBLE (810 -620);
FORCEADD GND..1
(800 -750);
FORCEPROP 3 LASTPIN (800 -700) SIG_NAME GND\g
J 0
(810 -690);
DISPLAY 0.659574 (810 -690);
PAINT MONO (810 -690);
DISPLAY INVISIBLE (810 -690);
FORCEPROP 2 LAST CDS_LIB mstr_symbols
J 0
(800 -750);
PAINT MONO (800 -750);
DISPLAY INVISIBLE (800 -750);
FORCEPROP 1 LAST PATH I123
J 0
(875 -750);
DISPLAY 0.872340 (875 -750);
PAINT AQUA (875 -750);
DISPLAY INVISIBLE (875 -750);
FORCEPROP 1 LAST VOLTAGE 0
J 0
(800 -750);
PAINT SKYBLUE (800 -750);
DISPLAY INVISIBLE (800 -750);
FORCEPROP 1 LAST SIZE 1B
J 0
(875 -800);
DISPLAY 1.723404 (875 -800);
PAINT GREEN (875 -800);
DISPLAY INVISIBLE (875 -800);
FORCEPROP 2 LAST BOM_COST PROC_VRD_VCCIN_CPU0
J 0
(425 -675);
DISPLAY 1.446809 (425 -675);
PAINT MONO (425 -675);
DISPLAY INVISIBLE (425 -675);
FORCEPROP 2 LAST ROOM PVCCIN_CPU0_PWR_VR
J 0
(250 -675);
DISPLAY 1.936170 (250 -675);
PAINT ORANGE (250 -675);
DISPLAY INVISIBLE (250 -675);
FORCEPROP 1 LAST BODY_TYPE PLUMBING
J 0
(755 -793);
DISPLAY 0.340426 (755 -793);
PAINT GREEN (755 -793);
DISPLAY INVISIBLE (755 -793);
FORCEPROP 1 LAST HDL_POWER GND
J 0
(800 -600);
DISPLAY 1.723404 (800 -600);
PAINT GREEN (800 -600);
DISPLAY INVISIBLE (800 -600);
FORCEADD 3D01R5F-GP..1
(2575 -750);
FORCEPROP 1 LAST LOCATION RT7
J 0
(2600 -670);
DISPLAY 0.617021 (2600 -670);
PAINT GREEN (2600 -670);
FORCEPROP 0 LAST STATUS NOPOP
J 0
(2600 -925);
DISPLAY 1.021277 (2600 -925);
PAINT ORANGE (2600 -925);
FORCEPROP 1 LAST VALUE 3D01R5F-GP
J 0
(2600 -775);
DISPLAY 0.617021 (2600 -775);
PAINT GREEN (2600 -775);
FORCEPROP 2 LASTPIN (2575 -625) SIG_NAME UN$227$3D01R5F-GP$I124$1
J 0
(2585 -615);
DISPLAY 0.659574 (2585 -615);
PAINT MONO (2585 -615);
DISPLAY INVISIBLE (2585 -615);
FORCEPROP 1 LAST PACK_TYPE SMD-RG5
J 0
(2575 -750);
DISPLAY 0.617021 (2575 -750);
PAINT GREEN (2575 -750);
DISPLAY INVISIBLE (2575 -750);
FORCEPROP 1 LAST PART_NUMBER 64.3R015.16L
J 0
(2575 -750);
DISPLAY 0.617021 (2575 -750);
PAINT GREEN (2575 -750);
DISPLAY INVISIBLE (2575 -750);
FORCEPROP 2 LAST CDS_LIB w_hdl
J 0
(2575 -750);
PAINT MONO (2575 -750);
DISPLAY INVISIBLE (2575 -750);
FORCEPROP 1 LAST PATH I124
J 0
(2575 -750);
DISPLAY 0.617021 (2575 -750);
PAINT GREEN (2575 -750);
DISPLAY INVISIBLE (2575 -750);
FORCEPROP 1 LAST CDS_LMAN_SYM_OUTLINE -50,75,50,-75
J 0
(2575 -750);
DISPLAY 0.468085 (2575 -750);
PAINT GREEN (2575 -750);
DISPLAY INVISIBLE (2575 -750);
FORCEADD 3D01R5F-GP..1
(2600 1400);
FORCEPROP 1 LAST LOCATION RT6
J 0
(2625 1480);
DISPLAY 0.617021 (2625 1480);
PAINT GREEN (2625 1480);
FORCEPROP 0 LAST STATUS NOPOP
J 0
(2675 1350);
DISPLAY 1.021277 (2675 1350);
PAINT ORANGE (2675 1350);
FORCEPROP 1 LAST VALUE 3D01R5F-GP
J 0
(2650 1400);
DISPLAY 0.617021 (2650 1400);
PAINT GREEN (2650 1400);
FORCEPROP 1 LAST CDS_LMAN_SYM_OUTLINE -50,75,50,-75
J 0
(2600 1400);
DISPLAY 0.468085 (2600 1400);
PAINT GREEN (2600 1400);
DISPLAY INVISIBLE (2600 1400);
FORCEPROP 1 LAST PATH I125
J 0
(2600 1400);
DISPLAY 0.617021 (2600 1400);
PAINT GREEN (2600 1400);
DISPLAY INVISIBLE (2600 1400);
FORCEPROP 2 LAST CDS_LIB w_hdl
J 0
(2600 1400);
PAINT MONO (2600 1400);
DISPLAY INVISIBLE (2600 1400);
FORCEPROP 1 LAST PART_NUMBER 64.3R015.16L
J 0
(2600 1400);
DISPLAY 0.617021 (2600 1400);
PAINT GREEN (2600 1400);
DISPLAY INVISIBLE (2600 1400);
FORCEPROP 1 LAST PACK_TYPE SMD-RG5
J 0
(2600 1400);
DISPLAY 0.617021 (2600 1400);
PAINT GREEN (2600 1400);
DISPLAY INVISIBLE (2600 1400);
FORCEPROP 2 LASTPIN (2600 1525) SIG_NAME UN$227$3D01R5F-GP$I125$1
J 0
(2610 1535);
DISPLAY 0.659574 (2610 1535);
PAINT MONO (2610 1535);
DISPLAY INVISIBLE (2610 1535);
FORCEADD RES..1
(-75 1950);
FORCEPROP 1 LAST PACK_TYPE 0402
J 0
(25 1800);
DISPLAY 0.617021 (25 1800);
PAINT SKYBLUE (25 1800);
FORCEPROP 1 LAST WATTAGE 1/16W
J 2
(-100 1800);
DISPLAY 0.617021 (-100 1800);
PAINT SKYBLUE (-100 1800);
FORCEPROP 1 LAST LOCATION RT5
J 0
(-200 1975);
DISPLAY 0.617021 (-200 1975);
PAINT AQUA (-200 1975);
FORCEPROP 1 LAST PART_NUMBER G21497-005
J 0
(-175 1900);
DISPLAY 0.617021 (-175 1900);
PAINT BLUE (-175 1900);
FORCEPROP 1 LAST TOLERANCE 5%
J 0
(-75 1850);
DISPLAY 0.617021 (-75 1850);
PAINT SKYBLUE (-75 1850);
FORCEPROP 1 LAST MATERIAL CHIP
J 0
(-75 1800);
DISPLAY 0.617021 (-75 1800);
PAINT SKYBLUE (-75 1800);
FORCEPROP 1 LAST VALUE 0.0
J 2
(-100 1850);
DISPLAY 0.617021 (-100 1850);
PAINT SKYBLUE (-100 1850);
FORCEPROP 2 LAST BOM_COST DEBUG
J 0
(-125 2150);
DISPLAY 1.021277 (-125 2150);
PAINT ORANGE (-125 2150);
DISPLAY INVISIBLE (-125 2150);
FORCEPROP 2 LAST ROOM BMC_DEBUG_HEADER
J 0
(-125 2100);
DISPLAY 1.021277 (-125 2100);
PAINT ORANGE (-125 2100);
DISPLAY INVISIBLE (-125 2100);
FORCEPROP 1 LAST PATH I126
J 0
(-125 2100);
DISPLAY 0.978723 (-125 2100);
PAINT WHITE (-125 2100);
DISPLAY INVISIBLE (-125 2100);
FORCEPROP 2 LAST CDS_LIB mstr_discrete
J 0
(-75 1950);
PAINT MONO (-75 1950);
DISPLAY INVISIBLE (-75 1950);
FORCEPROP 1 LASTPIN (-175 1950) $PN 1
J 0
(-163 1962);
DISPLAY 0.787234 (-163 1962);
PAINT ORANGE (-163 1962);
DISPLAY INVISIBLE (-163 1962);
FORCEPROP 1 LASTPIN (25 1950) $PN 2
J 0
(-13 1962);
DISPLAY 0.787234 (-13 1962);
PAINT ORANGE (-13 1962);
DISPLAY INVISIBLE (-13 1962);
FORCEADD RES..1
(-200 -225);
FORCEPROP 1 LAST WATTAGE 1/16W
J 2
(-225 -375);
DISPLAY 0.617021 (-225 -375);
PAINT SKYBLUE (-225 -375);
FORCEPROP 1 LAST TOLERANCE 5%
J 0
(-200 -325);
DISPLAY 0.617021 (-200 -325);
PAINT SKYBLUE (-200 -325);
FORCEPROP 1 LAST MATERIAL CHIP
J 0
(-200 -375);
DISPLAY 0.617021 (-200 -375);
PAINT SKYBLUE (-200 -375);
FORCEPROP 1 LAST PACK_TYPE 0402
J 0
(-100 -375);
DISPLAY 0.617021 (-100 -375);
PAINT SKYBLUE (-100 -375);
FORCEPROP 1 LAST LOCATION RT8
J 0
(-250 -175);
DISPLAY 0.617021 (-250 -175);
PAINT AQUA (-250 -175);
FORCEPROP 1 LAST PART_NUMBER G21497-005
J 0
(-300 -275);
DISPLAY 0.617021 (-300 -275);
PAINT BLUE (-300 -275);
FORCEPROP 1 LAST VALUE 0.0
J 2
(-225 -325);
DISPLAY 0.617021 (-225 -325);
PAINT SKYBLUE (-225 -325);
FORCEPROP 2 LAST ROOM BMC_DEBUG_HEADER
J 0
(-250 -75);
DISPLAY 1.021277 (-250 -75);
PAINT ORANGE (-250 -75);
DISPLAY INVISIBLE (-250 -75);
FORCEPROP 2 LAST BOM_COST DEBUG
J 0
(-250 -25);
DISPLAY 1.021277 (-250 -25);
PAINT ORANGE (-250 -25);
DISPLAY INVISIBLE (-250 -25);
FORCEPROP 1 LAST PATH I127
J 0
(-250 -75);
DISPLAY 0.978723 (-250 -75);
PAINT WHITE (-250 -75);
DISPLAY INVISIBLE (-250 -75);
FORCEPROP 2 LAST CDS_LIB mstr_discrete
J 0
(-200 -225);
PAINT MONO (-200 -225);
DISPLAY INVISIBLE (-200 -225);
FORCEPROP 1 LASTPIN (-300 -225) $PN 1
J 0
(-288 -213);
DISPLAY 0.787234 (-288 -213);
PAINT ORANGE (-288 -213);
DISPLAY INVISIBLE (-288 -213);
FORCEPROP 1 LASTPIN (-100 -225) $PN 2
J 0
(-138 -213);
DISPLAY 0.787234 (-138 -213);
PAINT ORANGE (-138 -213);
DISPLAY INVISIBLE (-138 -213);
FORCEADD GND..1
(2350 1400);
FORCEPROP 3 LASTPIN (2350 1450) SIG_NAME GND\g
J 0
(2360 1460);
DISPLAY 0.659574 (2360 1460);
PAINT MONO (2360 1460);
DISPLAY INVISIBLE (2360 1460);
FORCEPROP 1 LAST PATH I19
J 0
(2425 1400);
DISPLAY 0.893617 (2425 1400);
PAINT AQUA (2425 1400);
DISPLAY INVISIBLE (2425 1400);
FORCEPROP 1 LAST SIZE 1B
J 0
(2425 1350);
DISPLAY 1.723404 (2425 1350);
PAINT GREEN (2425 1350);
DISPLAY INVISIBLE (2425 1350);
FORCEPROP 2 LAST CDS_LIB mstr_symbols
J 0
(2350 1400);
DISPLAY 1.936170 (2350 1400);
PAINT ORANGE (2350 1400);
DISPLAY INVISIBLE (2350 1400);
FORCEPROP 1 LAST VOLTAGE 0
J 0
(2350 1400);
PAINT SKYBLUE (2350 1400);
DISPLAY INVISIBLE (2350 1400);
FORCEPROP 2 LAST ROOM VDDQ_KLM_PWR_VR
J 0
(1800 1475);
DISPLAY 1.936170 (1800 1475);
PAINT ORANGE (1800 1475);
DISPLAY INVISIBLE (1800 1475);
FORCEPROP 2 LAST BOM_COST VDDQ_KLM_PWR_VR
J 0
(1975 1475);
DISPLAY 1.446809 (1975 1475);
PAINT MONO (1975 1475);
DISPLAY INVISIBLE (1975 1475);
FORCEPROP 1 LAST BODY_TYPE PLUMBING
J 0
(2305 1357);
DISPLAY 0.340426 (2305 1357);
PAINT GREEN (2305 1357);
DISPLAY INVISIBLE (2305 1357);
FORCEPROP 1 LAST HDL_POWER GND
J 0
(2350 1550);
DISPLAY 1.723404 (2350 1550);
PAINT GREEN (2350 1550);
DISPLAY INVISIBLE (2350 1550);
FORCEADD OFFPAGE..2
(3225 2700);
FORCEPROP 2 LAST $XR0 226 
J 0
(3414 2700);
DISPLAY 0.638298 (3414 2700);
PAINT MONO (3414 2700);
FORCEPROP 2 LAST BOM_COST VDDQ_KLM_PWR_VR
J 0
(3425 2750);
DISPLAY 1.446809 (3425 2750);
PAINT MONO (3425 2750);
DISPLAY INVISIBLE (3425 2750);
FORCEPROP 2 LAST PATH I3
J 0
(3415 2750);
DISPLAY 1.021277 (3415 2750);
PAINT ORANGE (3415 2750);
DISPLAY INVISIBLE (3415 2750);
FORCEPROP 2 LAST CDS_LIB mstr_standard
J 0
(3225 2700);
DISPLAY 1.936170 (3225 2700);
PAINT ORANGE (3225 2700);
DISPLAY INVISIBLE (3225 2700);
FORCEPROP 2 LAST ROOM VDDQ_KLM_PWR_VR
J 0
(2825 2775);
DISPLAY 1.936170 (2825 2775);
PAINT ORANGE (2825 2775);
DISPLAY INVISIBLE (2825 2775);
FORCEPROP 1 LAST OFFPAGE TRUE
J 0
(3550 2575);
DISPLAY 1.723404 (3550 2575);
PAINT GREEN (3550 2575);
DISPLAY INVISIBLE (3550 2575);
FORCEPROP 1 LAST COMMENT_BODY TRUE
J 0
(3180 2605);
DISPLAY 1.723404 (3180 2605);
PAINT GREEN (3180 2605);
DISPLAY INVISIBLE (3180 2605);
FORCEADD OFFPAGE..1
(-1800 2050);
FORCEPROP 2 LASTPIN (-1750 2050) SIG_NAME VR_PVDDQ_KLM_PWM1
J 0
(-1735 2060);
DISPLAY 0.617021 (-1735 2060);
PAINT ORANGE (-1735 2060);
FORCEPROP 2 LAST $XR0 226 
J 0
(-2052 2050);
DISPLAY 0.638298 (-2052 2050);
PAINT MONO (-2052 2050);
FORCEPROP 2 LAST CDS_LIB mstr_standard
J 0
(-1800 2050);
DISPLAY 1.936170 (-1800 2050);
PAINT ORANGE (-1800 2050);
DISPLAY INVISIBLE (-1800 2050);
FORCEPROP 2 LAST PATH I33
J 0
(-2080 2100);
DISPLAY 1.021277 (-2080 2100);
PAINT ORANGE (-2080 2100);
DISPLAY INVISIBLE (-2080 2100);
FORCEPROP 2 LAST ROOM VDDQ_KLM_PWR_VR
J 0
(-2200 2125);
DISPLAY 1.936170 (-2200 2125);
PAINT ORANGE (-2200 2125);
DISPLAY INVISIBLE (-2200 2125);
FORCEPROP 2 LAST BOM_COST VDDQ_KLM_PWR_VR
J 0
(-2050 2100);
DISPLAY 1.446809 (-2050 2100);
PAINT MONO (-2050 2100);
DISPLAY INVISIBLE (-2050 2100);
FORCEPROP 1 LAST OFFPAGE TRUE
J 0
(-1475 1925);
DISPLAY 1.680851 (-1475 1925);
PAINT GREEN (-1475 1925);
DISPLAY INVISIBLE (-1475 1925);
FORCEPROP 1 LAST COMMENT_BODY TRUE
J 0
(-1675 1950);
DISPLAY 1.680851 (-1675 1950);
PAINT GREEN (-1675 1950);
DISPLAY INVISIBLE (-1675 1950);
FORCEADD GND..1
(-2650 2000);
FORCEPROP 3 LASTPIN (-2650 2050) SIG_NAME GND\g
J 0
(-2640 2060);
DISPLAY 0.659574 (-2640 2060);
PAINT MONO (-2640 2060);
DISPLAY INVISIBLE (-2640 2060);
FORCEPROP 2 LAST BOM_COST VDDQ_KLM_PWR_VR
J 0
(-3025 2075);
DISPLAY 1.446809 (-3025 2075);
PAINT MONO (-3025 2075);
DISPLAY INVISIBLE (-3025 2075);
FORCEPROP 2 LAST ROOM VDDQ_KLM_PWR_VR
J 0
(-3200 2075);
DISPLAY 1.936170 (-3200 2075);
PAINT ORANGE (-3200 2075);
DISPLAY INVISIBLE (-3200 2075);
FORCEPROP 2 LAST CDS_LIB mstr_symbols
J 0
(-2650 2000);
DISPLAY 1.936170 (-2650 2000);
PAINT ORANGE (-2650 2000);
DISPLAY INVISIBLE (-2650 2000);
FORCEPROP 1 LAST VOLTAGE 0
J 0
(-2650 2000);
PAINT SKYBLUE (-2650 2000);
DISPLAY INVISIBLE (-2650 2000);
FORCEPROP 1 LAST SIZE 1B
J 0
(-2575 1950);
DISPLAY 1.723404 (-2575 1950);
PAINT GREEN (-2575 1950);
DISPLAY INVISIBLE (-2575 1950);
FORCEPROP 1 LAST PATH I35
J 0
(-2575 2000);
DISPLAY 0.893617 (-2575 2000);
PAINT AQUA (-2575 2000);
DISPLAY INVISIBLE (-2575 2000);
FORCEPROP 1 LAST BODY_TYPE PLUMBING
J 0
(-2695 1957);
DISPLAY 0.340426 (-2695 1957);
PAINT GREEN (-2695 1957);
DISPLAY INVISIBLE (-2695 1957);
FORCEPROP 1 LAST HDL_POWER GND
J 0
(-2650 2150);
DISPLAY 1.723404 (-2650 2150);
PAINT GREEN (-2650 2150);
DISPLAY INVISIBLE (-2650 2150);
FORCEADD OFFPAGE..2
(3200 3025);
FORCEPROP 2 LAST $XR0 226 
J 0
(3389 3025);
DISPLAY 0.638298 (3389 3025);
PAINT MONO (3389 3025);
FORCEPROP 2 LAST BOM_COST VDDQ_KLM_PWR_VR
J 0
(3400 3075);
DISPLAY 1.446809 (3400 3075);
PAINT MONO (3400 3075);
DISPLAY INVISIBLE (3400 3075);
FORCEPROP 2 LAST PATH I4
J 0
(3390 3075);
DISPLAY 1.021277 (3390 3075);
PAINT ORANGE (3390 3075);
DISPLAY INVISIBLE (3390 3075);
FORCEPROP 2 LAST CDS_LIB mstr_standard
J 2
(3200 3025);
DISPLAY 1.936170 (3200 3025);
PAINT ORANGE (3200 3025);
DISPLAY INVISIBLE (3200 3025);
FORCEPROP 2 LAST ROOM VDDQ_KLM_PWR_VR
J 0
(2800 3100);
DISPLAY 1.936170 (2800 3100);
PAINT ORANGE (2800 3100);
DISPLAY INVISIBLE (2800 3100);
FORCEPROP 1 LAST OFFPAGE TRUE
J 0
(3525 2900);
DISPLAY 1.723404 (3525 2900);
PAINT GREEN (3525 2900);
DISPLAY INVISIBLE (3525 2900);
FORCEPROP 1 LAST COMMENT_BODY TRUE
J 0
(3155 2930);
DISPLAY 1.723404 (3155 2930);
PAINT GREEN (3155 2930);
DISPLAY INVISIBLE (3155 2930);
FORCEADD CAP..1
R 2
(-950 1850);
FORCEPROP 1 LAST PACK_TYPE 0402
J 2
(-1000 1650);
DISPLAY 0.617021 (-1000 1650);
PAINT SKYBLUE (-1000 1650);
FORCEPROP 1 LASTPIN (-950 1950) $PN 1
J 2
(-960 1930);
DISPLAY 0.617021 (-960 1930);
PAINT ORANGE (-960 1930);
FORCEPROP 1 LAST LOCATION C1A18
J 2
(-1000 1950);
DISPLAY 0.617021 (-1000 1950);
PAINT AQUA (-1000 1950);
FORCEPROP 1 LAST VALUE 0.220UF
J 2
(-1000 1900);
DISPLAY 0.617021 (-1000 1900);
PAINT SKYBLUE (-1000 1900);
FORCEPROP 1 LAST VOLTAGE 16V
J 2
(-1000 1850);
DISPLAY 0.617021 (-1000 1850);
PAINT SKYBLUE (-1000 1850);
FORCEPROP 1 LASTPIN (-950 1750) $PN 2
J 2
(-960 1730);
DISPLAY 0.617021 (-960 1730);
PAINT ORANGE (-960 1730);
FORCEPROP 1 LAST PART_NUMBER A36096-104
J 2
(-1000 1700);
DISPLAY 0.617021 (-1000 1700);
PAINT BLUE (-1000 1700);
FORCEPROP 1 LAST TOLERANCE 10%
J 2
(-1000 1800);
DISPLAY 0.617021 (-1000 1800);
PAINT SKYBLUE (-1000 1800);
FORCEPROP 1 LAST MATERIAL X7R
J 2
(-1000 1750);
DISPLAY 0.617021 (-1000 1750);
PAINT SKYBLUE (-1000 1750);
FORCEPROP 2 LAST SEC_TYPE 0402
J 0
(-1000 2050);
DISPLAY 1.021277 (-1000 2050);
PAINT ORANGE (-1000 2050);
DISPLAY INVISIBLE (-1000 2050);
FORCEPROP 0 LAST SPOF TRUE
J 0
(-1000 2050);
DISPLAY 1.021277 (-1000 2050);
PAINT ORANGE (-1000 2050);
DISPLAY INVISIBLE (-1000 2050);
FORCEPROP 2 LAST SEC 1
J 0
(-1000 2050);
DISPLAY 0.680851 (-1000 2050);
PAINT MONO (-1000 2050);
DISPLAY INVISIBLE (-1000 2050);
FORCEPROP 2 LAST ROOM VDDQ_KLM_PWR_VR
J 0
(-1025 2000);
DISPLAY 1.361702 (-1025 2000);
PAINT ORANGE (-1025 2000);
DISPLAY INVISIBLE (-1025 2000);
FORCEPROP 1 LAST PATH I44
J 2
(-1000 2000);
DISPLAY 0.978723 (-1000 2000);
PAINT WHITE (-1000 2000);
DISPLAY INVISIBLE (-1000 2000);
FORCEPROP 2 LAST CDS_LOCATION C1A18
J 2
(-1000 1950);
DISPLAY 0.617021 (-1000 1950);
PAINT AQUA (-1000 1950);
DISPLAY INVISIBLE (-1000 1950);
FORCEPROP 2 LAST CDS_LIB mstr_discrete
J 0
(-950 1850);
PAINT ORANGE (-950 1850);
DISPLAY INVISIBLE (-950 1850);
FORCEADD CAP..1
(-2650 2450);
FORCEPROP 1 LAST LOCATION C9L11
J 0
(-2600 2550);
DISPLAY 0.617021 (-2600 2550);
PAINT AQUA (-2600 2550);
FORCEPROP 1 LAST PART_NUMBER C95333-007
J 0
(-2600 2300);
DISPLAY 0.617021 (-2600 2300);
PAINT BLUE (-2600 2300);
FORCEPROP 1 LAST VALUE 10UF
J 0
(-2600 2500);
DISPLAY 0.617021 (-2600 2500);
PAINT SKYBLUE (-2600 2500);
FORCEPROP 1 LAST TOLERANCE 10%
J 0
(-2600 2400);
DISPLAY 0.617021 (-2600 2400);
PAINT SKYBLUE (-2600 2400);
FORCEPROP 1 LAST PACK_TYPE 0805
J 0
(-2600 2250);
DISPLAY 0.617021 (-2600 2250);
PAINT SKYBLUE (-2600 2250);
FORCEPROP 1 LAST VOLTAGE 16V
J 0
(-2600 2450);
DISPLAY 0.617021 (-2600 2450);
PAINT SKYBLUE (-2600 2450);
FORCEPROP 1 LAST MATERIAL X6S
J 0
(-2600 2350);
DISPLAY 0.617021 (-2600 2350);
PAINT SKYBLUE (-2600 2350);
FORCEPROP 1 LASTPIN (-2650 2350) $PN 2
J 0
(-2640 2330);
DISPLAY 0.617021 (-2640 2330);
PAINT ORANGE (-2640 2330);
FORCEPROP 1 LASTPIN (-2650 2550) $PN 1
J 0
(-2640 2530);
DISPLAY 0.617021 (-2640 2530);
PAINT ORANGE (-2640 2530);
FORCEPROP 2 LAST SEC_TYPE 0805
J 0
(-2600 2675);
DISPLAY 1.021277 (-2600 2675);
PAINT ORANGE (-2600 2675);
DISPLAY INVISIBLE (-2600 2675);
FORCEPROP 2 LAST SEC 1
J 0
(-2600 2675);
DISPLAY 0.680851 (-2600 2675);
PAINT MONO (-2600 2675);
DISPLAY INVISIBLE (-2600 2675);
FORCEPROP 1 LAST PATH I45
J 0
(-2600 2600);
DISPLAY 1.319149 (-2600 2600);
PAINT WHITE (-2600 2600);
DISPLAY INVISIBLE (-2600 2600);
FORCEPROP 2 LAST ROOM VDDQ_KLM_PWR_VR
J 0
(-2600 2600);
DISPLAY 1.361702 (-2600 2600);
PAINT ORANGE (-2600 2600);
DISPLAY INVISIBLE (-2600 2600);
FORCEPROP 2 LAST CDS_LOCATION C9L11
J 0
(-2600 2550);
DISPLAY 0.617021 (-2600 2550);
PAINT AQUA (-2600 2550);
DISPLAY INVISIBLE (-2600 2550);
FORCEPROP 2 LAST CDS_LIB mstr_discrete
J 0
(-2650 2450);
PAINT ORANGE (-2650 2450);
DISPLAY INVISIBLE (-2650 2450);
FORCEADD CAP..1
(-2400 2400);
FORCEPROP 1 LAST LOCATION C9L10
J 0
(-2350 2500);
DISPLAY 0.617021 (-2350 2500);
PAINT AQUA (-2350 2500);
FORCEPROP 1 LAST PART_NUMBER C95333-007
J 0
(-2350 2250);
DISPLAY 0.617021 (-2350 2250);
PAINT BLUE (-2350 2250);
FORCEPROP 1 LAST VALUE 10UF
J 0
(-2350 2450);
DISPLAY 0.617021 (-2350 2450);
PAINT SKYBLUE (-2350 2450);
FORCEPROP 1 LAST TOLERANCE 10%
J 0
(-2350 2350);
DISPLAY 0.617021 (-2350 2350);
PAINT SKYBLUE (-2350 2350);
FORCEPROP 1 LAST PACK_TYPE 0805
J 0
(-2350 2200);
DISPLAY 0.617021 (-2350 2200);
PAINT SKYBLUE (-2350 2200);
FORCEPROP 1 LAST VOLTAGE 16V
J 0
(-2350 2400);
DISPLAY 0.617021 (-2350 2400);
PAINT SKYBLUE (-2350 2400);
FORCEPROP 1 LAST MATERIAL X6S
J 0
(-2350 2300);
DISPLAY 0.617021 (-2350 2300);
PAINT SKYBLUE (-2350 2300);
FORCEPROP 1 LASTPIN (-2400 2500) $PN 1
J 0
(-2390 2480);
DISPLAY 0.617021 (-2390 2480);
PAINT ORANGE (-2390 2480);
FORCEPROP 1 LASTPIN (-2400 2300) $PN 2
J 0
(-2390 2280);
DISPLAY 0.617021 (-2390 2280);
PAINT ORANGE (-2390 2280);
FORCEPROP 2 LAST SEC 1
J 0
(-2350 2625);
DISPLAY 0.680851 (-2350 2625);
PAINT MONO (-2350 2625);
DISPLAY INVISIBLE (-2350 2625);
FORCEPROP 2 LAST SEC_TYPE 0805
J 0
(-2350 2625);
DISPLAY 1.021277 (-2350 2625);
PAINT ORANGE (-2350 2625);
DISPLAY INVISIBLE (-2350 2625);
FORCEPROP 1 LAST PATH I46
J 0
(-2350 2550);
DISPLAY 1.319149 (-2350 2550);
PAINT WHITE (-2350 2550);
DISPLAY INVISIBLE (-2350 2550);
FORCEPROP 2 LAST ROOM VDDQ_KLM_PWR_VR
J 0
(-2350 2550);
DISPLAY 1.361702 (-2350 2550);
PAINT ORANGE (-2350 2550);
DISPLAY INVISIBLE (-2350 2550);
FORCEPROP 2 LAST CDS_LOCATION C9L10
J 0
(-2350 2500);
DISPLAY 0.617021 (-2350 2500);
PAINT AQUA (-2350 2500);
DISPLAY INVISIBLE (-2350 2500);
FORCEPROP 2 LAST CDS_LIB mstr_discrete
J 0
(-2400 2400);
PAINT ORANGE (-2400 2400);
DISPLAY INVISIBLE (-2400 2400);
FORCEADD CAP..1
(-2175 2425);
FORCEPROP 1 LAST LOCATION C9L6
J 0
(-2125 2525);
DISPLAY 0.617021 (-2125 2525);
PAINT AQUA (-2125 2525);
FORCEPROP 1 LAST PART_NUMBER C95333-007
J 0
(-2125 2275);
DISPLAY 0.617021 (-2125 2275);
PAINT BLUE (-2125 2275);
FORCEPROP 1 LAST VALUE 10UF
J 0
(-2125 2475);
DISPLAY 0.617021 (-2125 2475);
PAINT SKYBLUE (-2125 2475);
FORCEPROP 1 LAST TOLERANCE 10%
J 0
(-2125 2375);
DISPLAY 0.617021 (-2125 2375);
PAINT SKYBLUE (-2125 2375);
FORCEPROP 1 LAST PACK_TYPE 0805
J 0
(-2125 2225);
DISPLAY 0.617021 (-2125 2225);
PAINT SKYBLUE (-2125 2225);
FORCEPROP 1 LAST VOLTAGE 16V
J 0
(-2125 2425);
DISPLAY 0.617021 (-2125 2425);
PAINT SKYBLUE (-2125 2425);
FORCEPROP 1 LAST MATERIAL X6S
J 0
(-2125 2325);
DISPLAY 0.617021 (-2125 2325);
PAINT SKYBLUE (-2125 2325);
FORCEPROP 1 LASTPIN (-2175 2525) $PN 1
J 0
(-2165 2505);
DISPLAY 0.617021 (-2165 2505);
PAINT ORANGE (-2165 2505);
FORCEPROP 1 LASTPIN (-2175 2325) $PN 2
J 0
(-2165 2305);
DISPLAY 0.617021 (-2165 2305);
PAINT ORANGE (-2165 2305);
FORCEPROP 2 LAST ROOM VDDQ_KLM_PWR_VR
J 0
(-2125 2575);
DISPLAY 1.361702 (-2125 2575);
PAINT ORANGE (-2125 2575);
DISPLAY INVISIBLE (-2125 2575);
FORCEPROP 1 LAST PATH I47
J 0
(-2125 2575);
DISPLAY 1.319149 (-2125 2575);
PAINT WHITE (-2125 2575);
DISPLAY INVISIBLE (-2125 2575);
FORCEPROP 2 LAST SEC 1
J 0
(-2125 2650);
DISPLAY 0.680851 (-2125 2650);
PAINT MONO (-2125 2650);
DISPLAY INVISIBLE (-2125 2650);
FORCEPROP 2 LAST SEC_TYPE 0805
J 0
(-2125 2650);
DISPLAY 1.021277 (-2125 2650);
PAINT ORANGE (-2125 2650);
DISPLAY INVISIBLE (-2125 2650);
FORCEPROP 2 LAST CDS_LOCATION C9L6
J 0
(-2125 2525);
DISPLAY 0.617021 (-2125 2525);
PAINT AQUA (-2125 2525);
DISPLAY INVISIBLE (-2125 2525);
FORCEPROP 2 LAST CDS_LIB mstr_discrete
J 0
(-2175 2425);
PAINT ORANGE (-2175 2425);
DISPLAY INVISIBLE (-2175 2425);
FORCEADD CAP..1
(-1900 2425);
FORCEPROP 1 LAST LOCATION C1A19
J 0
(-1850 2525);
DISPLAY 0.617021 (-1850 2525);
PAINT AQUA (-1850 2525);
FORCEPROP 1 LAST PART_NUMBER D97712-011
J 0
(-1850 2275);
DISPLAY 0.617021 (-1850 2275);
PAINT BLUE (-1850 2275);
FORCEPROP 1 LAST VALUE 1.0UF
J 0
(-1850 2475);
DISPLAY 0.617021 (-1850 2475);
PAINT SKYBLUE (-1850 2475);
FORCEPROP 1 LAST TOLERANCE 10%
J 0
(-1850 2375);
DISPLAY 0.617021 (-1850 2375);
PAINT SKYBLUE (-1850 2375);
FORCEPROP 1 LAST PACK_TYPE 0402
J 0
(-1850 2225);
DISPLAY 0.617021 (-1850 2225);
PAINT SKYBLUE (-1850 2225);
FORCEPROP 1 LAST VOLTAGE 16V
J 0
(-1850 2425);
DISPLAY 0.617021 (-1850 2425);
PAINT SKYBLUE (-1850 2425);
FORCEPROP 1 LAST MATERIAL X6S
J 0
(-1850 2325);
DISPLAY 0.617021 (-1850 2325);
PAINT SKYBLUE (-1850 2325);
FORCEPROP 1 LASTPIN (-1900 2325) $PN 2
J 0
(-1890 2305);
DISPLAY 0.617021 (-1890 2305);
PAINT ORANGE (-1890 2305);
FORCEPROP 1 LASTPIN (-1900 2525) $PN 1
J 0
(-1890 2505);
DISPLAY 0.617021 (-1890 2505);
PAINT ORANGE (-1890 2505);
FORCEPROP 2 LAST ROOM VDDQ_KLM_PWR_VR
J 0
(-1850 2575);
DISPLAY 1.361702 (-1850 2575);
PAINT ORANGE (-1850 2575);
DISPLAY INVISIBLE (-1850 2575);
FORCEPROP 1 LAST PATH I48
J 0
(-1850 2575);
DISPLAY 1.319149 (-1850 2575);
PAINT WHITE (-1850 2575);
DISPLAY INVISIBLE (-1850 2575);
FORCEPROP 2 LAST SEC 1
J 0
(-1850 2650);
DISPLAY 0.680851 (-1850 2650);
PAINT MONO (-1850 2650);
DISPLAY INVISIBLE (-1850 2650);
FORCEPROP 2 LAST SEC_TYPE 0402
J 0
(-1850 2650);
DISPLAY 1.021277 (-1850 2650);
PAINT ORANGE (-1850 2650);
DISPLAY INVISIBLE (-1850 2650);
FORCEPROP 2 LAST CDS_LIB mstr_discrete
J 0
(-1900 2425);
PAINT ORANGE (-1900 2425);
DISPLAY INVISIBLE (-1900 2425);
FORCEPROP 2 LAST CDS_LOCATION C1A19
J 0
(-1850 2525);
DISPLAY 0.617021 (-1850 2525);
PAINT AQUA (-1850 2525);
DISPLAY INVISIBLE (-1850 2525);
FORCEADD CAP..1
(-1350 2425);
FORCEPROP 1 LAST PACK_TYPE 0402
J 0
(-1300 2225);
DISPLAY 0.617021 (-1300 2225);
PAINT SKYBLUE (-1300 2225);
FORCEPROP 1 LAST PART_NUMBER D97712-011
J 0
(-1300 2275);
DISPLAY 0.617021 (-1300 2275);
PAINT BLUE (-1300 2275);
FORCEPROP 1 LAST VOLTAGE 16V
J 0
(-1300 2425);
DISPLAY 0.617021 (-1300 2425);
PAINT SKYBLUE (-1300 2425);
FORCEPROP 1 LAST TOLERANCE 10%
J 0
(-1300 2375);
DISPLAY 0.617021 (-1300 2375);
PAINT SKYBLUE (-1300 2375);
FORCEPROP 1 LAST VALUE 1.0UF
J 0
(-1300 2475);
DISPLAY 0.617021 (-1300 2475);
PAINT SKYBLUE (-1300 2475);
FORCEPROP 1 LASTPIN (-1350 2325) $PN 2
J 0
(-1340 2305);
DISPLAY 0.617021 (-1340 2305);
PAINT ORANGE (-1340 2305);
FORCEPROP 1 LASTPIN (-1350 2525) $PN 1
J 0
(-1340 2505);
DISPLAY 0.617021 (-1340 2505);
PAINT ORANGE (-1340 2505);
FORCEPROP 1 LAST MATERIAL X6S
J 0
(-1300 2325);
DISPLAY 0.617021 (-1300 2325);
PAINT SKYBLUE (-1300 2325);
FORCEPROP 1 LAST LOCATION C1B20
J 0
(-1300 2525);
DISPLAY 0.617021 (-1300 2525);
PAINT AQUA (-1300 2525);
FORCEPROP 2 LAST SEC_TYPE 0402
J 0
(-1300 2650);
DISPLAY 1.021277 (-1300 2650);
PAINT ORANGE (-1300 2650);
DISPLAY INVISIBLE (-1300 2650);
FORCEPROP 2 LAST SEC 1
J 0
(-1300 2650);
DISPLAY 0.680851 (-1300 2650);
PAINT MONO (-1300 2650);
DISPLAY INVISIBLE (-1300 2650);
FORCEPROP 1 LAST PATH I50
J 0
(-1300 2575);
DISPLAY 1.319149 (-1300 2575);
PAINT WHITE (-1300 2575);
DISPLAY INVISIBLE (-1300 2575);
FORCEPROP 2 LAST ROOM VDDQ_KLM_PWR_VR
J 0
(-1300 2575);
DISPLAY 1.361702 (-1300 2575);
PAINT ORANGE (-1300 2575);
DISPLAY INVISIBLE (-1300 2575);
FORCEPROP 2 LAST CDS_LIB mstr_discrete
J 0
(-1350 2425);
PAINT ORANGE (-1350 2425);
DISPLAY INVISIBLE (-1350 2425);
FORCEADD CAP_A..1
(-1675 2375);
FORCEPROP 1 LAST VOLTAGE 16V
J 0
(-1625 2375);
DISPLAY 0.617021 (-1625 2375);
PAINT SKYBLUE (-1625 2375);
FORCEPROP 1 LAST TOLERANCE 10%
J 0
(-1625 2325);
DISPLAY 0.617021 (-1625 2325);
PAINT SKYBLUE (-1625 2325);
FORCEPROP 1 LAST MATERIAL X7R
J 0
(-1625 2275);
DISPLAY 0.617021 (-1625 2275);
PAINT SKYBLUE (-1625 2275);
FORCEPROP 1 LAST PART_NUMBER A36096-030
J 0
(-1625 2225);
DISPLAY 0.617021 (-1625 2225);
PAINT BLUE (-1625 2225);
FORCEPROP 1 LAST LOCATION C1A10
J 0
(-1625 2475);
DISPLAY 0.617021 (-1625 2475);
PAINT AQUA (-1625 2475);
FORCEPROP 1 LAST VALUE 0.1UF
J 0
(-1625 2425);
DISPLAY 0.617021 (-1625 2425);
PAINT SKYBLUE (-1625 2425);
FORCEPROP 1 LAST PACK_TYPE 0402V
J 0
(-1625 2175);
DISPLAY 0.617021 (-1625 2175);
PAINT SKYBLUE (-1625 2175);
FORCEPROP 1 LASTPIN (-1675 2475) $PN 1
J 0
(-1665 2455);
DISPLAY 0.617021 (-1665 2455);
PAINT ORANGE (-1665 2455);
FORCEPROP 1 LASTPIN (-1675 2275) $PN 2
J 0
(-1665 2255);
DISPLAY 0.617021 (-1665 2255);
PAINT ORANGE (-1665 2255);
FORCEPROP 2 LAST SEC 1
J 0
(-1625 2600);
DISPLAY 0.680851 (-1625 2600);
PAINT MONO (-1625 2600);
DISPLAY INVISIBLE (-1625 2600);
FORCEPROP 2 LAST SEC_TYPE 0402V
J 0
(-1625 2600);
DISPLAY 1.021277 (-1625 2600);
PAINT ORANGE (-1625 2600);
DISPLAY INVISIBLE (-1625 2600);
FORCEPROP 1 LAST PATH I51
J 0
(-1625 2525);
DISPLAY 0.978723 (-1625 2525);
PAINT WHITE (-1625 2525);
DISPLAY INVISIBLE (-1625 2525);
FORCEPROP 2 LAST ROOM VDDQ_KLM_PWR_VR
J 0
(-1625 2525);
DISPLAY 1.361702 (-1625 2525);
PAINT ORANGE (-1625 2525);
DISPLAY INVISIBLE (-1625 2525);
FORCEPROP 2 LAST CDS_SEC 1
J 0
(-1625 2525);
PAINT ORANGE (-1625 2525);
DISPLAY INVISIBLE (-1625 2525);
FORCEPROP 2 LAST CDS_LIB dev_discrete
J 0
(-1675 2375);
PAINT ORANGE (-1675 2375);
DISPLAY INVISIBLE (-1675 2375);
FORCEPROP 2 LAST CDS_LOCATION C1A10
J 0
(-1625 2475);
DISPLAY 0.617021 (-1625 2475);
PAINT AQUA (-1625 2475);
DISPLAY INVISIBLE (-1625 2475);
FORCEADD RES..1
(-1100 3025);
FORCEPROP 1 LAST PART_NUMBER G21796-090
J 0
(-1225 2950);
DISPLAY 0.617021 (-1225 2950);
PAINT BLUE (-1225 2950);
FORCEPROP 1 LAST PACK_TYPE 0402
J 0
(-1050 2900);
DISPLAY 0.617021 (-1050 2900);
PAINT SKYBLUE (-1050 2900);
FORCEPROP 1 LAST MATERIAL CHIP
J 0
(-1025 2850);
DISPLAY 0.617021 (-1025 2850);
PAINT SKYBLUE (-1025 2850);
FORCEPROP 1 LASTPIN (-1000 3025) $PN 2
J 0
(-1038 3037);
DISPLAY 0.617021 (-1038 3037);
PAINT ORANGE (-1038 3037);
FORCEPROP 1 LAST LOCATION R9L9
J 0
(-1150 3075);
DISPLAY 0.617021 (-1150 3075);
PAINT AQUA (-1150 3075);
FORCEPROP 1 LASTPIN (-1200 3025) $PN 1
J 0
(-1188 3037);
DISPLAY 0.617021 (-1188 3037);
PAINT ORANGE (-1188 3037);
FORCEPROP 1 LAST WATTAGE 1/16W
J 2
(-1075 2850);
DISPLAY 0.617021 (-1075 2850);
PAINT SKYBLUE (-1075 2850);
FORCEPROP 1 LAST TOLERANCE 1%
J 0
(-1150 2900);
DISPLAY 0.617021 (-1150 2900);
PAINT SKYBLUE (-1150 2900);
FORCEPROP 1 LAST VALUE 1.0
J 2
(-1200 2900);
DISPLAY 0.617021 (-1200 2900);
PAINT SKYBLUE (-1200 2900);
FORCEPROP 2 LAST SEC_TYPE 0402
J 0
(-1150 3250);
DISPLAY 1.021277 (-1150 3250);
PAINT ORANGE (-1150 3250);
DISPLAY INVISIBLE (-1150 3250);
FORCEPROP 2 LAST SEC 1
J 0
(-1150 3250);
DISPLAY 0.680851 (-1150 3250);
PAINT MONO (-1150 3250);
DISPLAY INVISIBLE (-1150 3250);
FORCEPROP 2 LAST CDS_LOCATION R9L9
J 0
(-1150 3075);
DISPLAY 0.617021 (-1150 3075);
PAINT AQUA (-1150 3075);
DISPLAY INVISIBLE (-1150 3075);
FORCEPROP 1 LAST PATH I52
J 0
(-1150 3175);
DISPLAY 1.319149 (-1150 3175);
PAINT WHITE (-1150 3175);
DISPLAY INVISIBLE (-1150 3175);
FORCEPROP 2 LAST ROOM VDDQ_KLM_PWR_VR
J 0
(-1150 3125);
DISPLAY 1.361702 (-1150 3125);
PAINT ORANGE (-1150 3125);
DISPLAY INVISIBLE (-1150 3125);
FORCEPROP 2 LAST CDS_LIB mstr_discrete
J 0
(-1100 3025);
PAINT ORANGE (-1100 3025);
DISPLAY INVISIBLE (-1100 3025);
FORCEADD CAP_A..1
R 2
(-675 2425);
FORCEPROP 1 LAST PART_NUMBER D97712-004
J 2
(-725 2275);
DISPLAY 0.617021 (-725 2275);
PAINT BLUE (-725 2275);
FORCEPROP 1 LASTPIN (-675 2525) $PN 1
J 2
(-685 2505);
DISPLAY 0.617021 (-685 2505);
PAINT ORANGE (-685 2505);
FORCEPROP 1 LASTPIN (-675 2325) $PN 2
J 2
(-685 2305);
DISPLAY 0.617021 (-685 2305);
PAINT ORANGE (-685 2305);
FORCEPROP 1 LAST LOCATION C1A2
J 2
(-725 2525);
DISPLAY 0.617021 (-725 2525);
PAINT AQUA (-725 2525);
FORCEPROP 1 LAST VALUE 1.0UF
J 2
(-725 2475);
DISPLAY 0.617021 (-725 2475);
PAINT SKYBLUE (-725 2475);
FORCEPROP 1 LAST TOLERANCE 10%
J 2
(-725 2375);
DISPLAY 0.617021 (-725 2375);
PAINT SKYBLUE (-725 2375);
FORCEPROP 1 LAST PACK_TYPE 0402V
J 2
(-725 2225);
DISPLAY 0.617021 (-725 2225);
PAINT SKYBLUE (-725 2225);
FORCEPROP 1 LAST VOLTAGE 6.3V
J 2
(-725 2425);
DISPLAY 0.617021 (-725 2425);
PAINT SKYBLUE (-725 2425);
FORCEPROP 1 LAST MATERIAL X6S
J 2
(-725 2325);
DISPLAY 0.617021 (-725 2325);
PAINT SKYBLUE (-725 2325);
FORCEPROP 2 LAST CDS_SEC 1
J 0
(-725 2575);
PAINT ORANGE (-725 2575);
DISPLAY INVISIBLE (-725 2575);
FORCEPROP 2 LAST SEC_TYPE 0402V
J 0
(-725 2650);
DISPLAY 1.021277 (-725 2650);
PAINT ORANGE (-725 2650);
DISPLAY INVISIBLE (-725 2650);
FORCEPROP 2 LAST SEC 1
J 0
(-725 2650);
DISPLAY 0.680851 (-725 2650);
PAINT MONO (-725 2650);
DISPLAY INVISIBLE (-725 2650);
FORCEPROP 1 LAST PATH I53
J 2
(-725 2575);
DISPLAY 0.978723 (-725 2575);
PAINT WHITE (-725 2575);
DISPLAY INVISIBLE (-725 2575);
FORCEPROP 2 LAST ROOM VDDQ_KLM_PWR_VR
J 0
(-725 2575);
DISPLAY 1.361702 (-725 2575);
PAINT ORANGE (-725 2575);
DISPLAY INVISIBLE (-725 2575);
FORCEPROP 2 LAST CDS_LOCATION C1A2
J 2
(-725 2525);
DISPLAY 0.617021 (-725 2525);
PAINT AQUA (-725 2525);
DISPLAY INVISIBLE (-725 2525);
FORCEPROP 2 LAST CDS_LIB dev_discrete
J 0
(-675 2425);
PAINT ORANGE (-675 2425);
DISPLAY INVISIBLE (-675 2425);
FORCEADD CAP..1
(-575 2425);
FORCEPROP 1 LAST LOCATION C1B21
J 0
(-525 2525);
DISPLAY 0.617021 (-525 2525);
PAINT AQUA (-525 2525);
FORCEPROP 1 LAST PART_NUMBER A36096-155
J 0
(-525 2275);
DISPLAY 0.617021 (-525 2275);
PAINT BLUE (-525 2275);
FORCEPROP 1 LAST VALUE 0.22UF
J 0
(-525 2475);
DISPLAY 0.617021 (-525 2475);
PAINT SKYBLUE (-525 2475);
FORCEPROP 1 LAST TOLERANCE 10%
J 0
(-525 2375);
DISPLAY 0.617021 (-525 2375);
PAINT SKYBLUE (-525 2375);
FORCEPROP 1 LAST PACK_TYPE 0402
J 0
(-525 2225);
DISPLAY 0.617021 (-525 2225);
PAINT SKYBLUE (-525 2225);
FORCEPROP 1 LAST VOLTAGE 16V
J 0
(-525 2425);
DISPLAY 0.617021 (-525 2425);
PAINT SKYBLUE (-525 2425);
FORCEPROP 1 LAST MATERIAL X7R
J 0
(-525 2325);
DISPLAY 0.617021 (-525 2325);
PAINT SKYBLUE (-525 2325);
FORCEPROP 1 LASTPIN (-575 2525) $PN 1
J 0
(-565 2505);
DISPLAY 0.617021 (-565 2505);
PAINT ORANGE (-565 2505);
FORCEPROP 1 LASTPIN (-575 2325) $PN 2
J 0
(-565 2305);
DISPLAY 0.617021 (-565 2305);
PAINT ORANGE (-565 2305);
FORCEPROP 2 LAST SEC_TYPE 0402
J 0
(-525 2650);
DISPLAY 1.021277 (-525 2650);
PAINT ORANGE (-525 2650);
DISPLAY INVISIBLE (-525 2650);
FORCEPROP 2 LAST SEC 1
J 0
(-525 2650);
DISPLAY 0.680851 (-525 2650);
PAINT MONO (-525 2650);
DISPLAY INVISIBLE (-525 2650);
FORCEPROP 1 LAST PATH I54
J 0
(-525 2575);
DISPLAY 1.319149 (-525 2575);
PAINT WHITE (-525 2575);
DISPLAY INVISIBLE (-525 2575);
FORCEPROP 2 LAST ROOM VDDQ_KLM_PWR_VR
J 0
(-525 2575);
DISPLAY 1.361702 (-525 2575);
PAINT ORANGE (-525 2575);
DISPLAY INVISIBLE (-525 2575);
FORCEPROP 2 LAST CDS_LIB mstr_discrete
J 0
(-575 2425);
PAINT ORANGE (-575 2425);
DISPLAY INVISIBLE (-575 2425);
FORCEADD INDUCTOR..1
(3075 1850);
FORCEPROP 1 LAST PACK_TYPE SM
J 0
(3240 1740);
DISPLAY 0.617021 (3240 1740);
PAINT SKYBLUE (3240 1740);
FORCEPROP 1 LAST MATERIAL IND
J 0
(3115 1740);
DISPLAY 0.617021 (3115 1740);
PAINT SKYBLUE (3115 1740);
FORCEPROP 1 LAST PART_NUMBER D92183-034
J 0
(2975 1800);
DISPLAY 0.617021 (2975 1800);
PAINT BLUE (2975 1800);
FORCEPROP 1 LAST VALUE 0.12UH
J 2
(3120 1740);
DISPLAY 0.617021 (3120 1740);
PAINT SKYBLUE (3120 1740);
FORCEPROP 1 LAST LOCATION L1A2
J 0
(3175 1900);
DISPLAY 0.617021 (3175 1900);
PAINT AQUA (3175 1900);
FORCEPROP 1 LASTPIN (2975 1850) $PN 1
J 0
(2975 1860);
DISPLAY 0.617021 (2975 1860);
PAINT WHITE (2975 1860);
FORCEPROP 1 LASTPIN (3175 1850) $PN 2
J 2
(3185 1860);
DISPLAY 0.617021 (3185 1860);
PAINT WHITE (3185 1860);
FORCEPROP 2 LAST SEC_TYPE SM
J 0
(2975 2075);
DISPLAY 1.021277 (2975 2075);
PAINT ORANGE (2975 2075);
DISPLAY INVISIBLE (2975 2075);
FORCEPROP 2 LAST SEC 1
J 0
(2975 2075);
DISPLAY 0.680851 (2975 2075);
PAINT MONO (2975 2075);
DISPLAY INVISIBLE (2975 2075);
FORCEPROP 1 LAST PATH I55
J 0
(2975 2000);
DISPLAY 1.319149 (2975 2000);
PAINT ORANGE (2975 2000);
DISPLAY INVISIBLE (2975 2000);
FORCEPROP 2 LAST CDS_LIB mstr_discrete
J 0
(3075 1850);
PAINT ORANGE (3075 1850);
DISPLAY INVISIBLE (3075 1850);
FORCEPROP 2 LAST CDS_LOCATION L1A2
J 0
(2975 1900);
DISPLAY 0.617021 (2975 1900);
PAINT AQUA (2975 1900);
DISPLAY INVISIBLE (2975 1900);
FORCEPROP 2 LAST ROOM VDDQ_KLM_PWR_VR
J 0
(2975 1950);
DISPLAY 1.361702 (2975 1950);
PAINT ORANGE (2975 1950);
DISPLAY INVISIBLE (2975 1950);
FORCEADD OFFPAGE..2
(3300 2275);
FORCEPROP 2 LAST $XR0 227 
J 0
(3489 2275);
DISPLAY 0.638298 (3489 2275);
PAINT MONO (3489 2275);
FORCEPROP 2 LAST $XR1 226 
J 0
(3609 2275);
DISPLAY 0.638298 (3609 2275);
PAINT MONO (3609 2275);
FORCEPROP 2 LAST ROOM VDDQ_KLM_PWR_VR
J 0
(2900 2350);
DISPLAY 1.936170 (2900 2350);
PAINT ORANGE (2900 2350);
DISPLAY INVISIBLE (2900 2350);
FORCEPROP 2 LAST CDS_LIB mstr_standard
J 0
(3300 2275);
PAINT ORANGE (3300 2275);
DISPLAY INVISIBLE (3300 2275);
FORCEPROP 2 LAST PATH I58
J 0
(3480 2350);
DISPLAY 1.361702 (3480 2350);
PAINT ORANGE (3480 2350);
DISPLAY INVISIBLE (3480 2350);
FORCEPROP 2 LAST BOM_COST VDDQ_KLM_PWR_VR
J 0
(3500 2325);
DISPLAY 1.446809 (3500 2325);
PAINT MONO (3500 2325);
DISPLAY INVISIBLE (3500 2325);
FORCEPROP 1 LAST OFFPAGE TRUE
J 0
(3625 2150);
DISPLAY 1.723404 (3625 2150);
PAINT GREEN (3625 2150);
DISPLAY INVISIBLE (3625 2150);
FORCEPROP 1 LAST COMMENT_BODY TRUE
J 0
(3255 2180);
DISPLAY 1.723404 (3255 2180);
PAINT GREEN (3255 2180);
DISPLAY INVISIBLE (3255 2180);
FORCEADD CAP..1
(4025 1650);
FORCEPROP 1 LAST LOCATION C1A12
J 0
(4075 1750);
DISPLAY 0.617021 (4075 1750);
PAINT AQUA (4075 1750);
FORCEPROP 1 LAST PART_NUMBER C95333-002
J 0
(4075 1500);
DISPLAY 0.617021 (4075 1500);
PAINT BLUE (4075 1500);
FORCEPROP 1 LAST VALUE 22UF
J 0
(4075 1700);
DISPLAY 0.617021 (4075 1700);
PAINT SKYBLUE (4075 1700);
FORCEPROP 1 LAST TOLERANCE 20%
J 0
(4075 1600);
DISPLAY 0.617021 (4075 1600);
PAINT SKYBLUE (4075 1600);
FORCEPROP 1 LAST PACK_TYPE 0805LF
J 0
(4075 1450);
DISPLAY 0.617021 (4075 1450);
PAINT SKYBLUE (4075 1450);
FORCEPROP 1 LAST MATERIAL X6S
J 0
(4075 1550);
DISPLAY 0.617021 (4075 1550);
PAINT SKYBLUE (4075 1550);
FORCEPROP 1 LASTPIN (4025 1750) $PN 1
J 0
(4035 1730);
DISPLAY 0.617021 (4035 1730);
PAINT GREEN (4035 1730);
FORCEPROP 1 LASTPIN (4025 1550) $PN 2
J 0
(4035 1530);
DISPLAY 0.617021 (4035 1530);
PAINT GREEN (4035 1530);
FORCEPROP 2 LAST BOM_COST VDDQ_KLM_PWR_VR
J 0
(4075 1800);
DISPLAY 1.446809 (4075 1800);
PAINT MONO (4075 1800);
DISPLAY INVISIBLE (4075 1800);
FORCEPROP 2 LAST SEC_TYPE 0805LF
J 0
(4080 1850);
DISPLAY 1.021277 (4080 1850);
PAINT ORANGE (4080 1850);
DISPLAY INVISIBLE (4080 1850);
FORCEPROP 2 LAST SEC 1
J 0
(4080 1850);
DISPLAY 0.680851 (4080 1850);
PAINT MONO (4080 1850);
DISPLAY INVISIBLE (4080 1850);
FORCEPROP 1 LAST PATH I6
J 0
(4075 1800);
DISPLAY 0.978723 (4075 1800);
PAINT WHITE (4075 1800);
DISPLAY INVISIBLE (4075 1800);
FORCEPROP 2 LAST ROOM VDDQ_KLM_PWR_VR
J 0
(4075 1800);
DISPLAY 1.446809 (4075 1800);
PAINT MONO (4075 1800);
DISPLAY INVISIBLE (4075 1800);
FORCEPROP 1 LAST VOLTAGE 4V
J 0
(4075 1650);
DISPLAY 1.446809 (4075 1650);
PAINT SKYBLUE (4075 1650);
DISPLAY INVISIBLE (4075 1650);
FORCEPROP 2 LAST CDS_LIB mstr_discrete
J 0
(4025 1650);
DISPLAY 1.936170 (4025 1650);
PAINT ORANGE (4025 1650);
DISPLAY INVISIBLE (4025 1650);
FORCEPROP 2 LAST CDS_LOCATION C1A12
J 0
(4075 1750);
DISPLAY 0.617021 (4075 1750);
PAINT AQUA (4075 1750);
DISPLAY INVISIBLE (4075 1750);
FORCEADD OFFPAGE..2
(3625 900);
FORCEPROP 2 LAST $XR0 226 
J 0
(3814 900);
DISPLAY 0.638298 (3814 900);
PAINT MONO (3814 900);
FORCEPROP 2 LAST ROOM VDDQ_KLM_PWR_VR
J 0
(3225 975);
DISPLAY 1.936170 (3225 975);
PAINT ORANGE (3225 975);
DISPLAY INVISIBLE (3225 975);
FORCEPROP 2 LAST CDS_LIB mstr_standard
J 0
(3625 900);
PAINT ORANGE (3625 900);
DISPLAY INVISIBLE (3625 900);
FORCEPROP 2 LAST PATH I61
J 0
(3805 975);
DISPLAY 1.361702 (3805 975);
PAINT ORANGE (3805 975);
DISPLAY INVISIBLE (3805 975);
FORCEPROP 2 LAST BOM_COST VDDQ_KLM_PWR_VR
J 0
(3825 950);
DISPLAY 1.446809 (3825 950);
PAINT MONO (3825 950);
DISPLAY INVISIBLE (3825 950);
FORCEPROP 1 LAST OFFPAGE TRUE
J 0
(3950 775);
DISPLAY 1.723404 (3950 775);
PAINT GREEN (3950 775);
DISPLAY INVISIBLE (3950 775);
FORCEPROP 1 LAST COMMENT_BODY TRUE
J 0
(3580 805);
DISPLAY 1.723404 (3580 805);
PAINT GREEN (3580 805);
DISPLAY INVISIBLE (3580 805);
FORCEADD OFFPAGE..2
(3600 550);
FORCEPROP 2 LAST $XR0 226 
J 0
(3789 550);
DISPLAY 0.638298 (3789 550);
PAINT MONO (3789 550);
FORCEPROP 2 LAST ROOM VDDQ_KLM_PWR_VR
J 0
(3200 625);
DISPLAY 1.936170 (3200 625);
PAINT ORANGE (3200 625);
DISPLAY INVISIBLE (3200 625);
FORCEPROP 2 LAST CDS_LIB mstr_standard
J 0
(3600 550);
PAINT ORANGE (3600 550);
DISPLAY INVISIBLE (3600 550);
FORCEPROP 2 LAST PATH I62
J 0
(3780 625);
DISPLAY 1.361702 (3780 625);
PAINT ORANGE (3780 625);
DISPLAY INVISIBLE (3780 625);
FORCEPROP 2 LAST BOM_COST VDDQ_KLM_PWR_VR
J 0
(3800 600);
DISPLAY 1.446809 (3800 600);
PAINT MONO (3800 600);
DISPLAY INVISIBLE (3800 600);
FORCEPROP 1 LAST OFFPAGE TRUE
J 0
(3925 425);
DISPLAY 1.723404 (3925 425);
PAINT GREEN (3925 425);
DISPLAY INVISIBLE (3925 425);
FORCEPROP 1 LAST COMMENT_BODY TRUE
J 0
(3555 455);
DISPLAY 1.723404 (3555 455);
PAINT GREEN (3555 455);
DISPLAY INVISIBLE (3555 455);
FORCEADD OFFPAGE..2
(3125 200);
FORCEPROP 2 LAST $XR1 226 
J 0
(3434 200);
DISPLAY 0.638298 (3434 200);
PAINT MONO (3434 200);
FORCEPROP 2 LAST $XR0 227 
J 0
(3314 200);
DISPLAY 0.638298 (3314 200);
PAINT MONO (3314 200);
FORCEPROP 2 LAST BOM_COST VDDQ_KLM_PWR_VR
J 0
(3325 250);
DISPLAY 1.446809 (3325 250);
PAINT MONO (3325 250);
DISPLAY INVISIBLE (3325 250);
FORCEPROP 2 LAST PATH I63
J 0
(3305 275);
DISPLAY 1.361702 (3305 275);
PAINT ORANGE (3305 275);
DISPLAY INVISIBLE (3305 275);
FORCEPROP 2 LAST CDS_LIB mstr_standard
J 0
(3125 200);
PAINT ORANGE (3125 200);
DISPLAY INVISIBLE (3125 200);
FORCEPROP 2 LAST ROOM VDDQ_KLM_PWR_VR
J 0
(2725 275);
DISPLAY 1.936170 (2725 275);
PAINT ORANGE (2725 275);
DISPLAY INVISIBLE (2725 275);
FORCEPROP 1 LAST OFFPAGE TRUE
J 0
(3450 75);
DISPLAY 1.723404 (3450 75);
PAINT GREEN (3450 75);
DISPLAY INVISIBLE (3450 75);
FORCEPROP 1 LAST COMMENT_BODY TRUE
J 0
(3080 105);
DISPLAY 1.723404 (3080 105);
PAINT GREEN (3080 105);
DISPLAY INVISIBLE (3080 105);
FORCEADD PVDDQ_KLM..1
(4025 -200);
FORCEPROP 3 LASTPIN (4025 -250) SIG_NAME PVDDQ_KLM\g
J 0
(4035 -240);
DISPLAY 0.659574 (4035 -240);
PAINT MONO (4035 -240);
DISPLAY INVISIBLE (4035 -240);
FORCEPROP 1 LAST VOLTAGE 1.2V
J 0
(3980 -243);
DISPLAY 0.340426 (3980 -243);
PAINT SKYBLUE (3980 -243);
DISPLAY INVISIBLE (3980 -243);
FORCEPROP 2 LAST BOM_COST VDDQ_KLM_PWR_VR
J 0
(4025 -100);
DISPLAY 1.446809 (4025 -100);
PAINT MONO (4025 -100);
DISPLAY INVISIBLE (4025 -100);
FORCEPROP 2 LAST CDS_LIB mstr_symbols
J 0
(4025 -200);
PAINT ORANGE (4025 -200);
DISPLAY INVISIBLE (4025 -200);
FORCEPROP 1 LAST PATH I64
J 0
(4075 -175);
DISPLAY 0.872340 (4075 -175);
PAINT AQUA (4075 -175);
DISPLAY INVISIBLE (4075 -175);
FORCEPROP 2 LAST ROOM VDDQ_KLM_PWR_VR
J 0
(4025 -100);
DISPLAY 1.936170 (4025 -100);
PAINT ORANGE (4025 -100);
DISPLAY INVISIBLE (4025 -100);
FORCEPROP 1 LAST BODY_TYPE PLUMBING
J 0
(3980 -243);
DISPLAY 0.340426 (3980 -243);
PAINT GREEN (3980 -243);
DISPLAY INVISIBLE (3980 -243);
FORCEPROP 1 LAST HDL_POWER PVDDQ_KLM
J 1
(4025 -150);
DISPLAY 0.872340 (4025 -150);
PAINT GREEN (4025 -150);
DISPLAY INVISIBLE (4025 -150);
FORCEADD INDUCTOR..1
(3150 -300);
FORCEPROP 1 LAST VALUE 0.12UH
J 2
(3145 -410);
DISPLAY 0.617021 (3145 -410);
PAINT SKYBLUE (3145 -410);
FORCEPROP 1 LAST MATERIAL IND
J 0
(3190 -410);
DISPLAY 0.617021 (3190 -410);
PAINT SKYBLUE (3190 -410);
FORCEPROP 1 LAST PACK_TYPE SM
J 0
(3315 -410);
DISPLAY 0.617021 (3315 -410);
PAINT SKYBLUE (3315 -410);
FORCEPROP 1 LASTPIN (3250 -300) $PN 2
J 2
(3260 -290);
DISPLAY 0.617021 (3260 -290);
PAINT WHITE (3260 -290);
FORCEPROP 1 LAST LOCATION L1A1
J 0
(3050 -250);
DISPLAY 0.617021 (3050 -250);
PAINT AQUA (3050 -250);
FORCEPROP 1 LASTPIN (3050 -300) $PN 1
J 0
(3050 -290);
DISPLAY 0.617021 (3050 -290);
PAINT WHITE (3050 -290);
FORCEPROP 1 LAST PART_NUMBER D92183-034
J 0
(3025 -350);
DISPLAY 0.617021 (3025 -350);
PAINT BLUE (3025 -350);
FORCEPROP 2 LAST ROOM VDDQ_KLM_PWR_VR
J 0
(3050 -200);
DISPLAY 1.361702 (3050 -200);
PAINT ORANGE (3050 -200);
DISPLAY INVISIBLE (3050 -200);
FORCEPROP 1 LAST PATH I65
J 0
(3050 -150);
DISPLAY 1.319149 (3050 -150);
PAINT ORANGE (3050 -150);
DISPLAY INVISIBLE (3050 -150);
FORCEPROP 2 LAST CDS_LOCATION L1A1
J 0
(3050 -250);
DISPLAY 0.617021 (3050 -250);
PAINT AQUA (3050 -250);
DISPLAY INVISIBLE (3050 -250);
FORCEPROP 2 LAST SEC 1
J 0
(3050 -75);
DISPLAY 0.680851 (3050 -75);
PAINT MONO (3050 -75);
DISPLAY INVISIBLE (3050 -75);
FORCEPROP 2 LAST SEC_TYPE SM
J 0
(3050 -75);
DISPLAY 1.021277 (3050 -75);
PAINT ORANGE (3050 -75);
DISPLAY INVISIBLE (3050 -75);
FORCEPROP 2 LAST CDS_LIB mstr_discrete
J 0
(3150 -300);
PAINT ORANGE (3150 -300);
DISPLAY INVISIBLE (3150 -300);
FORCEADD CAP..1
(4025 -500);
FORCEPROP 1 LAST TOLERANCE 20%
J 0
(4075 -550);
DISPLAY 0.617021 (4075 -550);
PAINT SKYBLUE (4075 -550);
FORCEPROP 1 LAST VALUE 22UF
J 0
(4075 -450);
DISPLAY 0.617021 (4075 -450);
PAINT SKYBLUE (4075 -450);
FORCEPROP 1 LAST LOCATION C1A1
J 0
(4075 -400);
DISPLAY 0.617021 (4075 -400);
PAINT AQUA (4075 -400);
FORCEPROP 1 LASTPIN (4025 -600) $PN 2
J 0
(4035 -620);
DISPLAY 0.617021 (4035 -620);
PAINT ORANGE (4035 -620);
FORCEPROP 1 LASTPIN (4025 -400) $PN 1
J 0
(4035 -420);
DISPLAY 0.617021 (4035 -420);
PAINT ORANGE (4035 -420);
FORCEPROP 1 LAST PACK_TYPE 0805LF
J 0
(4075 -700);
DISPLAY 0.617021 (4075 -700);
PAINT SKYBLUE (4075 -700);
FORCEPROP 1 LAST MATERIAL X6S
J 0
(4075 -600);
DISPLAY 0.617021 (4075 -600);
PAINT SKYBLUE (4075 -600);
FORCEPROP 1 LAST PART_NUMBER C95333-002
J 0
(4075 -650);
DISPLAY 0.617021 (4075 -650);
PAINT BLUE (4075 -650);
FORCEPROP 2 LAST CDS_LIB mstr_discrete
J 0
(4025 -500);
PAINT ORANGE (4025 -500);
DISPLAY INVISIBLE (4025 -500);
FORCEPROP 1 LAST VOLTAGE 4V
J 0
(4075 -500);
DISPLAY 1.446809 (4075 -500);
PAINT SKYBLUE (4075 -500);
DISPLAY INVISIBLE (4075 -500);
FORCEPROP 2 LAST ROOM VDDQ_KLM_PWR_VR
J 0
(4075 -350);
DISPLAY 1.446809 (4075 -350);
PAINT MONO (4075 -350);
DISPLAY INVISIBLE (4075 -350);
FORCEPROP 1 LAST PATH I68
J 0
(4075 -350);
DISPLAY 1.319149 (4075 -350);
PAINT WHITE (4075 -350);
DISPLAY INVISIBLE (4075 -350);
FORCEPROP 2 LAST CDS_LOCATION C1A1
J 0
(4075 -400);
DISPLAY 0.617021 (4075 -400);
PAINT AQUA (4075 -400);
DISPLAY INVISIBLE (4075 -400);
FORCEPROP 2 LAST BOM_COST VDDQ_KLM_PWR_VR
J 0
(4075 -350);
DISPLAY 1.446809 (4075 -350);
PAINT MONO (4075 -350);
DISPLAY INVISIBLE (4075 -350);
FORCEPROP 2 LAST SEC_TYPE 0805LF
J 0
(4080 -275);
DISPLAY 1.021277 (4080 -275);
PAINT ORANGE (4080 -275);
DISPLAY INVISIBLE (4080 -275);
FORCEPROP 2 LAST SEC 1
J 0
(4080 -275);
DISPLAY 0.680851 (4080 -275);
PAINT MONO (4080 -275);
DISPLAY INVISIBLE (4080 -275);
FORCEADD GND..1
(4025 -725);
FORCEPROP 3 LASTPIN (4025 -675) SIG_NAME GND\g
J 0
(4035 -665);
DISPLAY 0.659574 (4035 -665);
PAINT MONO (4035 -665);
DISPLAY INVISIBLE (4035 -665);
FORCEPROP 2 LAST ROOM VDDQ_KLM_PWR_VR
J 0
(3475 -650);
DISPLAY 1.936170 (3475 -650);
PAINT ORANGE (3475 -650);
DISPLAY INVISIBLE (3475 -650);
FORCEPROP 2 LAST BOM_COST VDDQ_KLM_PWR_VR
J 0
(3650 -650);
DISPLAY 1.446809 (3650 -650);
PAINT MONO (3650 -650);
DISPLAY INVISIBLE (3650 -650);
FORCEPROP 2 LAST CDS_LIB mstr_symbols
J 0
(4025 -725);
PAINT ORANGE (4025 -725);
DISPLAY INVISIBLE (4025 -725);
FORCEPROP 1 LAST VOLTAGE 0
J 0
(4025 -725);
PAINT SKYBLUE (4025 -725);
DISPLAY INVISIBLE (4025 -725);
FORCEPROP 1 LAST PATH I69
J 0
(4100 -725);
DISPLAY 1.170213 (4100 -725);
PAINT AQUA (4100 -725);
DISPLAY INVISIBLE (4100 -725);
FORCEPROP 1 LAST SIZE 1B
J 0
(4100 -775);
DISPLAY 1.723404 (4100 -775);
PAINT GREEN (4100 -775);
DISPLAY INVISIBLE (4100 -775);
FORCEPROP 1 LAST BODY_TYPE PLUMBING
J 0
(3980 -768);
DISPLAY 0.340426 (3980 -768);
PAINT GREEN (3980 -768);
DISPLAY INVISIBLE (3980 -768);
FORCEPROP 1 LAST HDL_POWER GND
J 0
(4025 -575);
DISPLAY 1.723404 (4025 -575);
PAINT GREEN (4025 -575);
DISPLAY INVISIBLE (4025 -575);
FORCEADD GND..1
(4025 1425);
FORCEPROP 3 LASTPIN (4025 1475) SIG_NAME GND\g
J 0
(4035 1485);
DISPLAY 0.659574 (4035 1485);
PAINT MONO (4035 1485);
DISPLAY INVISIBLE (4035 1485);
FORCEPROP 1 LAST SIZE 1B
J 0
(4100 1375);
DISPLAY 1.723404 (4100 1375);
PAINT GREEN (4100 1375);
DISPLAY INVISIBLE (4100 1375);
FORCEPROP 1 LAST PATH I7
J 0
(4100 1425);
DISPLAY 0.893617 (4100 1425);
PAINT AQUA (4100 1425);
DISPLAY INVISIBLE (4100 1425);
FORCEPROP 2 LAST BOM_COST VDDQ_KLM_PWR_VR
J 0
(3650 1500);
DISPLAY 1.446809 (3650 1500);
PAINT MONO (3650 1500);
DISPLAY INVISIBLE (3650 1500);
FORCEPROP 1 LAST VOLTAGE 0
J 0
(4025 1425);
PAINT SKYBLUE (4025 1425);
DISPLAY INVISIBLE (4025 1425);
FORCEPROP 2 LAST CDS_LIB mstr_symbols
J 0
(4025 1425);
DISPLAY 1.936170 (4025 1425);
PAINT ORANGE (4025 1425);
DISPLAY INVISIBLE (4025 1425);
FORCEPROP 2 LAST ROOM VDDQ_KLM_PWR_VR
J 0
(3475 1500);
DISPLAY 1.936170 (3475 1500);
PAINT ORANGE (3475 1500);
DISPLAY INVISIBLE (3475 1500);
FORCEPROP 1 LAST BODY_TYPE PLUMBING
J 0
(3980 1382);
DISPLAY 0.340426 (3980 1382);
PAINT GREEN (3980 1382);
DISPLAY INVISIBLE (3980 1382);
FORCEPROP 1 LAST HDL_POWER GND
J 0
(4025 1575);
DISPLAY 1.723404 (4025 1575);
PAINT GREEN (4025 1575);
DISPLAY INVISIBLE (4025 1575);
FORCEADD GND..1
(2350 -750);
FORCEPROP 3 LASTPIN (2350 -700) SIG_NAME GND\g
J 0
(2360 -690);
DISPLAY 0.659574 (2360 -690);
PAINT MONO (2360 -690);
DISPLAY INVISIBLE (2360 -690);
FORCEPROP 2 LAST ROOM VDDQ_KLM_PWR_VR
J 0
(1800 -675);
DISPLAY 1.936170 (1800 -675);
PAINT ORANGE (1800 -675);
DISPLAY INVISIBLE (1800 -675);
FORCEPROP 2 LAST BOM_COST VDDQ_KLM_PWR_VR
J 0
(1975 -675);
DISPLAY 1.446809 (1975 -675);
PAINT MONO (1975 -675);
DISPLAY INVISIBLE (1975 -675);
FORCEPROP 1 LAST SIZE 1B
J 0
(2425 -800);
DISPLAY 1.723404 (2425 -800);
PAINT GREEN (2425 -800);
DISPLAY INVISIBLE (2425 -800);
FORCEPROP 1 LAST VOLTAGE 0
J 0
(2350 -750);
PAINT SKYBLUE (2350 -750);
DISPLAY INVISIBLE (2350 -750);
FORCEPROP 2 LAST CDS_LIB mstr_symbols
J 0
(2350 -750);
PAINT ORANGE (2350 -750);
DISPLAY INVISIBLE (2350 -750);
FORCEPROP 1 LAST PATH I70
J 0
(2425 -750);
DISPLAY 1.170213 (2425 -750);
PAINT AQUA (2425 -750);
DISPLAY INVISIBLE (2425 -750);
FORCEPROP 1 LAST BODY_TYPE PLUMBING
J 0
(2305 -793);
DISPLAY 0.340426 (2305 -793);
PAINT GREEN (2305 -793);
DISPLAY INVISIBLE (2305 -793);
FORCEPROP 1 LAST HDL_POWER GND
J 0
(2350 -600);
DISPLAY 1.723404 (2350 -600);
PAINT GREEN (2350 -600);
DISPLAY INVISIBLE (2350 -600);
FORCEADD CAP..1
(-650 275);
FORCEPROP 1 LAST VALUE 0.22UF
J 0
(-600 325);
DISPLAY 0.617021 (-600 325);
PAINT SKYBLUE (-600 325);
FORCEPROP 1 LAST LOCATION C1A13
J 0
(-600 375);
DISPLAY 0.617021 (-600 375);
PAINT AQUA (-600 375);
FORCEPROP 1 LAST PACK_TYPE 0402
J 0
(-600 75);
DISPLAY 0.617021 (-600 75);
PAINT SKYBLUE (-600 75);
FORCEPROP 1 LASTPIN (-650 175) $PN 2
J 0
(-640 155);
DISPLAY 0.617021 (-640 155);
PAINT ORANGE (-640 155);
FORCEPROP 1 LAST MATERIAL X7R
J 0
(-600 175);
DISPLAY 0.617021 (-600 175);
PAINT SKYBLUE (-600 175);
FORCEPROP 1 LAST PART_NUMBER A36096-155
J 0
(-600 125);
DISPLAY 0.617021 (-600 125);
PAINT BLUE (-600 125);
FORCEPROP 1 LAST TOLERANCE 10%
J 0
(-600 225);
DISPLAY 0.617021 (-600 225);
PAINT SKYBLUE (-600 225);
FORCEPROP 1 LAST VOLTAGE 16V
J 0
(-600 275);
DISPLAY 0.617021 (-600 275);
PAINT SKYBLUE (-600 275);
FORCEPROP 1 LASTPIN (-650 375) $PN 1
J 0
(-640 355);
DISPLAY 0.617021 (-640 355);
PAINT ORANGE (-640 355);
FORCEPROP 2 LAST CDS_LIB mstr_discrete
J 0
(-650 275);
PAINT ORANGE (-650 275);
DISPLAY INVISIBLE (-650 275);
FORCEPROP 2 LAST CDS_LOCATION C1A13
J 0
(-600 375);
DISPLAY 0.617021 (-600 375);
PAINT AQUA (-600 375);
DISPLAY INVISIBLE (-600 375);
FORCEPROP 1 LAST PATH I72
J 0
(-600 425);
DISPLAY 1.319149 (-600 425);
PAINT WHITE (-600 425);
DISPLAY INVISIBLE (-600 425);
FORCEPROP 2 LAST ROOM VDDQ_KLM_PWR_VR
J 0
(-600 425);
DISPLAY 1.361702 (-600 425);
PAINT ORANGE (-600 425);
DISPLAY INVISIBLE (-600 425);
FORCEPROP 2 LAST SEC_TYPE 0402
J 0
(-600 500);
DISPLAY 1.021277 (-600 500);
PAINT ORANGE (-600 500);
DISPLAY INVISIBLE (-600 500);
FORCEPROP 2 LAST SEC 1
J 0
(-600 500);
DISPLAY 0.680851 (-600 500);
PAINT MONO (-600 500);
DISPLAY INVISIBLE (-600 500);
FORCEADD CAP_A..1
R 2
(-750 275);
FORCEPROP 1 LAST PART_NUMBER D97712-004
J 2
(-800 125);
DISPLAY 0.617021 (-800 125);
PAINT BLUE (-800 125);
FORCEPROP 1 LAST PACK_TYPE 0402V
J 2
(-800 75);
DISPLAY 0.617021 (-800 75);
PAINT SKYBLUE (-800 75);
FORCEPROP 1 LAST MATERIAL X6S
J 2
(-800 175);
DISPLAY 0.617021 (-800 175);
PAINT SKYBLUE (-800 175);
FORCEPROP 1 LAST TOLERANCE 10%
J 2
(-800 225);
DISPLAY 0.617021 (-800 225);
PAINT SKYBLUE (-800 225);
FORCEPROP 1 LAST VOLTAGE 6.3V
J 2
(-800 275);
DISPLAY 0.617021 (-800 275);
PAINT SKYBLUE (-800 275);
FORCEPROP 1 LAST VALUE 1.0UF
J 2
(-800 325);
DISPLAY 0.617021 (-800 325);
PAINT SKYBLUE (-800 325);
FORCEPROP 1 LAST LOCATION C1A11
J 2
(-800 375);
DISPLAY 0.617021 (-800 375);
PAINT AQUA (-800 375);
FORCEPROP 1 LASTPIN (-750 175) $PN 2
J 2
(-760 155);
DISPLAY 0.617021 (-760 155);
PAINT ORANGE (-760 155);
FORCEPROP 1 LASTPIN (-750 375) $PN 1
J 2
(-760 355);
DISPLAY 0.617021 (-760 355);
PAINT ORANGE (-760 355);
FORCEPROP 2 LAST CDS_SEC 1
J 0
(-800 425);
PAINT ORANGE (-800 425);
DISPLAY INVISIBLE (-800 425);
FORCEPROP 2 LAST CDS_LOCATION C1A11
J 2
(-800 375);
DISPLAY 0.617021 (-800 375);
PAINT AQUA (-800 375);
DISPLAY INVISIBLE (-800 375);
FORCEPROP 2 LAST SEC 1
J 0
(-800 500);
DISPLAY 0.680851 (-800 500);
PAINT MONO (-800 500);
DISPLAY INVISIBLE (-800 500);
FORCEPROP 2 LAST SEC_TYPE 0402V
J 0
(-800 500);
DISPLAY 1.021277 (-800 500);
PAINT ORANGE (-800 500);
DISPLAY INVISIBLE (-800 500);
FORCEPROP 2 LAST ROOM VDDQ_KLM_PWR_VR
J 0
(-800 425);
DISPLAY 1.361702 (-800 425);
PAINT ORANGE (-800 425);
DISPLAY INVISIBLE (-800 425);
FORCEPROP 1 LAST PATH I73
J 2
(-800 425);
DISPLAY 0.978723 (-800 425);
PAINT WHITE (-800 425);
DISPLAY INVISIBLE (-800 425);
FORCEPROP 2 LAST CDS_LIB dev_discrete
J 0
(-750 275);
PAINT ORANGE (-750 275);
DISPLAY INVISIBLE (-750 275);
FORCEADD CAP..1
R 2
(-950 -325);
FORCEPROP 1 LASTPIN (-950 -225) $PN 1
J 2
(-960 -245);
DISPLAY 0.617021 (-960 -245);
PAINT ORANGE (-960 -245);
FORCEPROP 1 LAST PART_NUMBER A36096-104
J 2
(-1000 -475);
DISPLAY 0.617021 (-1000 -475);
PAINT BLUE (-1000 -475);
FORCEPROP 1 LAST PACK_TYPE 0402
J 2
(-1000 -525);
DISPLAY 0.617021 (-1000 -525);
PAINT SKYBLUE (-1000 -525);
FORCEPROP 1 LAST MATERIAL X7R
J 2
(-1000 -425);
DISPLAY 0.617021 (-1000 -425);
PAINT SKYBLUE (-1000 -425);
FORCEPROP 1 LASTPIN (-950 -425) $PN 2
J 2
(-960 -445);
DISPLAY 0.617021 (-960 -445);
PAINT ORANGE (-960 -445);
FORCEPROP 1 LAST TOLERANCE 10%
J 2
(-1000 -375);
DISPLAY 0.617021 (-1000 -375);
PAINT SKYBLUE (-1000 -375);
FORCEPROP 1 LAST VOLTAGE 16V
J 2
(-1000 -325);
DISPLAY 0.617021 (-1000 -325);
PAINT SKYBLUE (-1000 -325);
FORCEPROP 1 LAST VALUE 0.220UF
J 2
(-1000 -275);
DISPLAY 0.617021 (-1000 -275);
PAINT SKYBLUE (-1000 -275);
FORCEPROP 1 LAST LOCATION C1A8
J 2
(-1000 -225);
DISPLAY 0.617021 (-1000 -225);
PAINT AQUA (-1000 -225);
FORCEPROP 2 LAST ROOM VDDQ_KLM_PWR_VR
J 0
(-1000 -175);
DISPLAY 1.361702 (-1000 -175);
PAINT ORANGE (-1000 -175);
DISPLAY INVISIBLE (-1000 -175);
FORCEPROP 2 LAST SEC_TYPE 0402
J 0
(-1000 -125);
DISPLAY 1.021277 (-1000 -125);
PAINT ORANGE (-1000 -125);
DISPLAY INVISIBLE (-1000 -125);
FORCEPROP 2 LAST CDS_LOCATION C1A8
J 2
(-1000 -225);
DISPLAY 0.617021 (-1000 -225);
PAINT AQUA (-1000 -225);
DISPLAY INVISIBLE (-1000 -225);
FORCEPROP 2 LAST SEC 1
J 0
(-1000 -125);
DISPLAY 0.680851 (-1000 -125);
PAINT MONO (-1000 -125);
DISPLAY INVISIBLE (-1000 -125);
FORCEPROP 0 LAST SPOF TRUE
J 0
(-1000 -125);
DISPLAY 1.021277 (-1000 -125);
PAINT ORANGE (-1000 -125);
DISPLAY INVISIBLE (-1000 -125);
FORCEPROP 1 LAST PATH I75
J 2
(-1000 -175);
DISPLAY 0.978723 (-1000 -175);
PAINT WHITE (-1000 -175);
DISPLAY INVISIBLE (-1000 -175);
FORCEPROP 2 LAST CDS_LIB mstr_discrete
J 0
(-950 -325);
PAINT ORANGE (-950 -325);
DISPLAY INVISIBLE (-950 -325);
FORCEADD RES..1
(-1050 825);
FORCEPROP 1 LAST WATTAGE 1/16W
J 2
(-1025 650);
DISPLAY 0.617021 (-1025 650);
PAINT SKYBLUE (-1025 650);
FORCEPROP 1 LAST VALUE 1.0
J 2
(-1150 700);
DISPLAY 0.617021 (-1150 700);
PAINT SKYBLUE (-1150 700);
FORCEPROP 1 LAST PART_NUMBER G21796-090
J 0
(-1175 750);
DISPLAY 0.617021 (-1175 750);
PAINT BLUE (-1175 750);
FORCEPROP 1 LAST TOLERANCE 1%
J 0
(-1100 700);
DISPLAY 0.617021 (-1100 700);
PAINT SKYBLUE (-1100 700);
FORCEPROP 1 LAST PACK_TYPE 0402
J 0
(-1000 700);
DISPLAY 0.617021 (-1000 700);
PAINT SKYBLUE (-1000 700);
FORCEPROP 1 LAST MATERIAL CHIP
J 0
(-975 650);
DISPLAY 0.617021 (-975 650);
PAINT SKYBLUE (-975 650);
FORCEPROP 1 LASTPIN (-950 825) $PN 2
J 0
(-988 837);
DISPLAY 0.617021 (-988 837);
PAINT ORANGE (-988 837);
FORCEPROP 1 LASTPIN (-1150 825) $PN 1
J 0
(-1138 837);
DISPLAY 0.617021 (-1138 837);
PAINT ORANGE (-1138 837);
FORCEPROP 1 LAST LOCATION R9L4
J 0
(-1100 875);
DISPLAY 0.617021 (-1100 875);
PAINT AQUA (-1100 875);
FORCEPROP 2 LAST CDS_LIB mstr_discrete
J 0
(-1050 825);
PAINT ORANGE (-1050 825);
DISPLAY INVISIBLE (-1050 825);
FORCEPROP 2 LAST CDS_LOCATION R9L4
J 0
(-1100 875);
DISPLAY 0.617021 (-1100 875);
PAINT AQUA (-1100 875);
DISPLAY INVISIBLE (-1100 875);
FORCEPROP 2 LAST ROOM VDDQ_KLM_PWR_VR
J 0
(-1100 925);
DISPLAY 1.361702 (-1100 925);
PAINT ORANGE (-1100 925);
DISPLAY INVISIBLE (-1100 925);
FORCEPROP 1 LAST PATH I76
J 0
(-1100 975);
DISPLAY 1.319149 (-1100 975);
PAINT WHITE (-1100 975);
DISPLAY INVISIBLE (-1100 975);
FORCEPROP 2 LAST SEC 1
J 0
(-1100 1050);
DISPLAY 0.680851 (-1100 1050);
PAINT MONO (-1100 1050);
DISPLAY INVISIBLE (-1100 1050);
FORCEPROP 2 LAST SEC_TYPE 0402
J 0
(-1100 1050);
DISPLAY 1.021277 (-1100 1050);
PAINT ORANGE (-1100 1050);
DISPLAY INVISIBLE (-1100 1050);
FORCEADD CAP..1
(-1275 300);
FORCEPROP 1 LAST PART_NUMBER D97712-011
J 0
(-1225 150);
DISPLAY 0.617021 (-1225 150);
PAINT BLUE (-1225 150);
FORCEPROP 1 LASTPIN (-1275 200) $PN 2
J 0
(-1265 180);
DISPLAY 0.617021 (-1265 180);
PAINT ORANGE (-1265 180);
FORCEPROP 1 LAST PACK_TYPE 0402
J 0
(-1225 100);
DISPLAY 0.617021 (-1225 100);
PAINT SKYBLUE (-1225 100);
FORCEPROP 1 LAST LOCATION C1A6
J 0
(-1225 400);
DISPLAY 0.617021 (-1225 400);
PAINT AQUA (-1225 400);
FORCEPROP 1 LASTPIN (-1275 400) $PN 1
J 0
(-1265 380);
DISPLAY 0.617021 (-1265 380);
PAINT ORANGE (-1265 380);
FORCEPROP 1 LAST VOLTAGE 16V
J 0
(-1225 300);
DISPLAY 0.617021 (-1225 300);
PAINT SKYBLUE (-1225 300);
FORCEPROP 1 LAST TOLERANCE 10%
J 0
(-1225 250);
DISPLAY 0.617021 (-1225 250);
PAINT SKYBLUE (-1225 250);
FORCEPROP 1 LAST VALUE 1.0UF
J 0
(-1225 350);
DISPLAY 0.617021 (-1225 350);
PAINT SKYBLUE (-1225 350);
FORCEPROP 1 LAST MATERIAL X6S
J 0
(-1225 200);
DISPLAY 0.617021 (-1225 200);
PAINT SKYBLUE (-1225 200);
FORCEPROP 2 LAST CDS_LOCATION C1A6
J 0
(-1225 400);
DISPLAY 0.617021 (-1225 400);
PAINT AQUA (-1225 400);
DISPLAY INVISIBLE (-1225 400);
FORCEPROP 2 LAST CDS_LIB mstr_discrete
J 0
(-1275 300);
PAINT ORANGE (-1275 300);
DISPLAY INVISIBLE (-1275 300);
FORCEPROP 1 LAST PATH I77
J 0
(-1225 450);
DISPLAY 1.319149 (-1225 450);
PAINT WHITE (-1225 450);
DISPLAY INVISIBLE (-1225 450);
FORCEPROP 2 LAST ROOM VDDQ_KLM_PWR_VR
J 0
(-1225 450);
DISPLAY 1.361702 (-1225 450);
PAINT ORANGE (-1225 450);
DISPLAY INVISIBLE (-1225 450);
FORCEPROP 2 LAST SEC_TYPE 0402
J 0
(-1225 525);
DISPLAY 1.021277 (-1225 525);
PAINT ORANGE (-1225 525);
DISPLAY INVISIBLE (-1225 525);
FORCEPROP 2 LAST SEC 1
J 0
(-1225 525);
DISPLAY 0.680851 (-1225 525);
PAINT MONO (-1225 525);
DISPLAY INVISIBLE (-1225 525);
FORCEADD CAP_A..1
(-1750 275);
FORCEPROP 1 LASTPIN (-1750 175) $PN 2
J 0
(-1740 155);
DISPLAY 0.617021 (-1740 155);
PAINT ORANGE (-1740 155);
FORCEPROP 1 LAST MATERIAL X7R
J 0
(-1700 175);
DISPLAY 0.617021 (-1700 175);
PAINT SKYBLUE (-1700 175);
FORCEPROP 1 LAST PACK_TYPE 0402V
J 0
(-1700 75);
DISPLAY 0.617021 (-1700 75);
PAINT SKYBLUE (-1700 75);
FORCEPROP 1 LAST PART_NUMBER A36096-030
J 0
(-1700 125);
DISPLAY 0.617021 (-1700 125);
PAINT BLUE (-1700 125);
FORCEPROP 1 LAST TOLERANCE 10%
J 0
(-1700 225);
DISPLAY 0.617021 (-1700 225);
PAINT SKYBLUE (-1700 225);
FORCEPROP 1 LASTPIN (-1750 375) $PN 1
J 0
(-1740 355);
DISPLAY 0.617021 (-1740 355);
PAINT ORANGE (-1740 355);
FORCEPROP 1 LAST VOLTAGE 16V
J 0
(-1700 275);
DISPLAY 0.617021 (-1700 275);
PAINT SKYBLUE (-1700 275);
FORCEPROP 1 LAST VALUE 0.1UF
J 0
(-1700 325);
DISPLAY 0.617021 (-1700 325);
PAINT SKYBLUE (-1700 325);
FORCEPROP 1 LAST LOCATION C1A20
J 0
(-1700 375);
DISPLAY 0.617021 (-1700 375);
PAINT AQUA (-1700 375);
FORCEPROP 2 LAST CDS_LIB dev_discrete
J 0
(-1750 275);
PAINT ORANGE (-1750 275);
DISPLAY INVISIBLE (-1750 275);
FORCEPROP 1 LAST PATH I78
J 0
(-1700 425);
DISPLAY 0.978723 (-1700 425);
PAINT WHITE (-1700 425);
DISPLAY INVISIBLE (-1700 425);
FORCEPROP 2 LAST CDS_LOCATION C1A20
J 0
(-1700 375);
DISPLAY 0.617021 (-1700 375);
PAINT AQUA (-1700 375);
DISPLAY INVISIBLE (-1700 375);
FORCEPROP 2 LAST CDS_SEC 1
J 0
(-1700 425);
PAINT ORANGE (-1700 425);
DISPLAY INVISIBLE (-1700 425);
FORCEPROP 2 LAST ROOM VDDQ_KLM_PWR_VR
J 0
(-1700 425);
DISPLAY 1.361702 (-1700 425);
PAINT ORANGE (-1700 425);
DISPLAY INVISIBLE (-1700 425);
FORCEPROP 2 LAST SEC_TYPE 0402V
J 0
(-1700 500);
DISPLAY 1.021277 (-1700 500);
PAINT ORANGE (-1700 500);
DISPLAY INVISIBLE (-1700 500);
FORCEPROP 2 LAST SEC 1
J 0
(-1700 500);
DISPLAY 0.680851 (-1700 500);
PAINT MONO (-1700 500);
DISPLAY INVISIBLE (-1700 500);
FORCEADD CAP..1
(-1975 275);
FORCEPROP 1 LAST PACK_TYPE 0402
J 0
(-1925 75);
DISPLAY 0.617021 (-1925 75);
PAINT SKYBLUE (-1925 75);
FORCEPROP 1 LAST MATERIAL X6S
J 0
(-1925 175);
DISPLAY 0.617021 (-1925 175);
PAINT SKYBLUE (-1925 175);
FORCEPROP 1 LASTPIN (-1975 175) $PN 2
J 0
(-1965 155);
DISPLAY 0.617021 (-1965 155);
PAINT ORANGE (-1965 155);
FORCEPROP 1 LAST PART_NUMBER D97712-011
J 0
(-1925 125);
DISPLAY 0.617021 (-1925 125);
PAINT BLUE (-1925 125);
FORCEPROP 1 LAST TOLERANCE 10%
J 0
(-1925 225);
DISPLAY 0.617021 (-1925 225);
PAINT SKYBLUE (-1925 225);
FORCEPROP 1 LASTPIN (-1975 375) $PN 1
J 0
(-1965 355);
DISPLAY 0.617021 (-1965 355);
PAINT ORANGE (-1965 355);
FORCEPROP 1 LAST VOLTAGE 16V
J 0
(-1925 275);
DISPLAY 0.617021 (-1925 275);
PAINT SKYBLUE (-1925 275);
FORCEPROP 1 LAST LOCATION C1A9
J 0
(-1925 375);
DISPLAY 0.617021 (-1925 375);
PAINT AQUA (-1925 375);
FORCEPROP 1 LAST VALUE 1.0UF
J 0
(-1925 325);
DISPLAY 0.617021 (-1925 325);
PAINT SKYBLUE (-1925 325);
FORCEPROP 2 LAST CDS_LIB mstr_discrete
J 0
(-1975 275);
PAINT ORANGE (-1975 275);
DISPLAY INVISIBLE (-1975 275);
FORCEPROP 2 LAST CDS_LOCATION C1A9
J 0
(-1925 375);
DISPLAY 0.617021 (-1925 375);
PAINT AQUA (-1925 375);
DISPLAY INVISIBLE (-1925 375);
FORCEPROP 1 LAST PATH I79
J 0
(-1925 425);
DISPLAY 1.319149 (-1925 425);
PAINT WHITE (-1925 425);
DISPLAY INVISIBLE (-1925 425);
FORCEPROP 2 LAST ROOM VDDQ_KLM_PWR_VR
J 0
(-1925 425);
DISPLAY 1.361702 (-1925 425);
PAINT ORANGE (-1925 425);
DISPLAY INVISIBLE (-1925 425);
FORCEPROP 2 LAST SEC_TYPE 0402
J 0
(-1925 500);
DISPLAY 1.021277 (-1925 500);
PAINT ORANGE (-1925 500);
DISPLAY INVISIBLE (-1925 500);
FORCEPROP 2 LAST SEC 1
J 0
(-1925 500);
DISPLAY 0.680851 (-1925 500);
PAINT MONO (-1925 500);
DISPLAY INVISIBLE (-1925 500);
FORCEADD CAP..1
(-2225 275);
FORCEPROP 1 LASTPIN (-2225 175) $PN 2
J 0
(-2215 155);
DISPLAY 0.617021 (-2215 155);
PAINT ORANGE (-2215 155);
FORCEPROP 1 LAST MATERIAL X6S
J 0
(-2175 175);
DISPLAY 0.617021 (-2175 175);
PAINT SKYBLUE (-2175 175);
FORCEPROP 1 LAST PACK_TYPE 0805
J 0
(-2175 75);
DISPLAY 0.617021 (-2175 75);
PAINT SKYBLUE (-2175 75);
FORCEPROP 1 LAST PART_NUMBER C95333-007
J 0
(-2175 125);
DISPLAY 0.617021 (-2175 125);
PAINT BLUE (-2175 125);
FORCEPROP 1 LAST TOLERANCE 10%
J 0
(-2175 225);
DISPLAY 0.617021 (-2175 225);
PAINT SKYBLUE (-2175 225);
FORCEPROP 1 LASTPIN (-2225 375) $PN 1
J 0
(-2215 355);
DISPLAY 0.617021 (-2215 355);
PAINT ORANGE (-2215 355);
FORCEPROP 1 LAST VOLTAGE 16V
J 0
(-2175 275);
DISPLAY 0.617021 (-2175 275);
PAINT SKYBLUE (-2175 275);
FORCEPROP 1 LAST VALUE 10UF
J 0
(-2175 325);
DISPLAY 0.617021 (-2175 325);
PAINT SKYBLUE (-2175 325);
FORCEPROP 1 LAST LOCATION C9L5
J 0
(-2175 375);
DISPLAY 0.617021 (-2175 375);
PAINT AQUA (-2175 375);
FORCEPROP 2 LAST CDS_LIB mstr_discrete
J 0
(-2225 275);
PAINT ORANGE (-2225 275);
DISPLAY INVISIBLE (-2225 275);
FORCEPROP 1 LAST PATH I80
J 0
(-2175 425);
DISPLAY 1.319149 (-2175 425);
PAINT WHITE (-2175 425);
DISPLAY INVISIBLE (-2175 425);
FORCEPROP 2 LAST CDS_LOCATION C9L5
J 0
(-2175 375);
DISPLAY 0.617021 (-2175 375);
PAINT AQUA (-2175 375);
DISPLAY INVISIBLE (-2175 375);
FORCEPROP 2 LAST ROOM VDDQ_KLM_PWR_VR
J 0
(-2175 425);
DISPLAY 1.361702 (-2175 425);
PAINT ORANGE (-2175 425);
DISPLAY INVISIBLE (-2175 425);
FORCEPROP 2 LAST SEC_TYPE 0805
J 0
(-2175 500);
DISPLAY 1.021277 (-2175 500);
PAINT ORANGE (-2175 500);
DISPLAY INVISIBLE (-2175 500);
FORCEPROP 2 LAST SEC 1
J 0
(-2175 500);
DISPLAY 0.680851 (-2175 500);
PAINT MONO (-2175 500);
DISPLAY INVISIBLE (-2175 500);
FORCEADD CAP..1
(-2475 225);
FORCEPROP 1 LASTPIN (-2475 125) $PN 2
J 0
(-2465 105);
DISPLAY 0.617021 (-2465 105);
PAINT ORANGE (-2465 105);
FORCEPROP 1 LAST MATERIAL X6S
J 0
(-2425 125);
DISPLAY 0.617021 (-2425 125);
PAINT SKYBLUE (-2425 125);
FORCEPROP 1 LAST PACK_TYPE 0805
J 0
(-2425 25);
DISPLAY 0.617021 (-2425 25);
PAINT SKYBLUE (-2425 25);
FORCEPROP 1 LAST TOLERANCE 10%
J 0
(-2425 175);
DISPLAY 0.617021 (-2425 175);
PAINT SKYBLUE (-2425 175);
FORCEPROP 1 LAST PART_NUMBER C95333-007
J 0
(-2425 75);
DISPLAY 0.617021 (-2425 75);
PAINT BLUE (-2425 75);
FORCEPROP 1 LAST VOLTAGE 16V
J 0
(-2425 225);
DISPLAY 0.617021 (-2425 225);
PAINT SKYBLUE (-2425 225);
FORCEPROP 1 LASTPIN (-2475 325) $PN 1
J 0
(-2465 305);
DISPLAY 0.617021 (-2465 305);
PAINT ORANGE (-2465 305);
FORCEPROP 1 LAST VALUE 10UF
J 0
(-2425 275);
DISPLAY 0.617021 (-2425 275);
PAINT SKYBLUE (-2425 275);
FORCEPROP 1 LAST LOCATION C9L13
J 0
(-2425 325);
DISPLAY 0.617021 (-2425 325);
PAINT AQUA (-2425 325);
FORCEPROP 2 LAST CDS_LIB mstr_discrete
J 0
(-2475 225);
PAINT ORANGE (-2475 225);
DISPLAY INVISIBLE (-2475 225);
FORCEPROP 2 LAST ROOM VDDQ_KLM_PWR_VR
J 0
(-2425 375);
DISPLAY 1.361702 (-2425 375);
PAINT ORANGE (-2425 375);
DISPLAY INVISIBLE (-2425 375);
FORCEPROP 1 LAST PATH I81
J 0
(-2425 375);
DISPLAY 1.319149 (-2425 375);
PAINT WHITE (-2425 375);
DISPLAY INVISIBLE (-2425 375);
FORCEPROP 2 LAST CDS_LOCATION C9L13
J 0
(-2425 325);
DISPLAY 0.617021 (-2425 325);
PAINT AQUA (-2425 325);
DISPLAY INVISIBLE (-2425 325);
FORCEPROP 2 LAST SEC 1
J 0
(-2425 450);
DISPLAY 0.680851 (-2425 450);
PAINT MONO (-2425 450);
DISPLAY INVISIBLE (-2425 450);
FORCEPROP 2 LAST SEC_TYPE 0805
J 0
(-2425 450);
DISPLAY 1.021277 (-2425 450);
PAINT ORANGE (-2425 450);
DISPLAY INVISIBLE (-2425 450);
FORCEADD OFFPAGE..1
(-1675 -100);
FORCEPROP 2 LAST $XR0 226 
J 0
(-1927 -100);
DISPLAY 0.638298 (-1927 -100);
PAINT MONO (-1927 -100);
FORCEPROP 2 LAST ROOM VDDQ_KLM_PWR_VR
J 0
(-2075 -25);
DISPLAY 1.936170 (-2075 -25);
PAINT ORANGE (-2075 -25);
DISPLAY INVISIBLE (-2075 -25);
FORCEPROP 2 LAST BOM_COST VDDQ_KLM_PWR_VR
J 0
(-1925 -50);
DISPLAY 1.446809 (-1925 -50);
PAINT MONO (-1925 -50);
DISPLAY INVISIBLE (-1925 -50);
FORCEPROP 2 LAST CDS_LIB mstr_standard
J 0
(-1675 -100);
PAINT ORANGE (-1675 -100);
DISPLAY INVISIBLE (-1675 -100);
FORCEPROP 2 LAST PATH I82
J 0
(-1620 -25);
DISPLAY 1.361702 (-1620 -25);
PAINT ORANGE (-1620 -25);
DISPLAY INVISIBLE (-1620 -25);
FORCEPROP 1 LAST OFFPAGE TRUE
J 0
(-1350 -225);
DISPLAY 1.680851 (-1350 -225);
PAINT GREEN (-1350 -225);
DISPLAY INVISIBLE (-1350 -225);
FORCEPROP 1 LAST COMMENT_BODY TRUE
J 0
(-1550 -200);
DISPLAY 1.680851 (-1550 -200);
PAINT GREEN (-1550 -200);
DISPLAY INVISIBLE (-1550 -200);
FORCEADD VCC_CORE..1
(-2725 750);
FORCEPROP 3 LASTPIN (-2725 700) SIG_NAME VR_FET_SW_P12V_STBY_PVDDQ_KLM\g
J 0
(-2715 710);
DISPLAY 0.659574 (-2715 710);
PAINT MONO (-2715 710);
DISPLAY INVISIBLE (-2715 710);
FORCEPROP 1 LAST HDL_POWER VR_FET_SW_P12V_STBY_PVDDQ_KLM
J 1
(-2600 800);
DISPLAY 0.617021 (-2600 800);
PAINT GREEN (-2600 800);
FORCEPROP 1 LAST PATH I83
J 0
(-2675 775);
DISPLAY 1.170213 (-2675 775);
PAINT AQUA (-2675 775);
DISPLAY INVISIBLE (-2675 775);
FORCEPROP 2 LAST CDS_LIB mstr_symbols
J 0
(-2725 750);
PAINT ORANGE (-2725 750);
DISPLAY INVISIBLE (-2725 750);
FORCEADD CAP..1
(-2725 275);
FORCEPROP 1 LASTPIN (-2725 175) $PN 2
J 0
(-2715 155);
DISPLAY 0.617021 (-2715 155);
PAINT ORANGE (-2715 155);
FORCEPROP 1 LAST MATERIAL X6S
J 0
(-2675 175);
DISPLAY 0.617021 (-2675 175);
PAINT SKYBLUE (-2675 175);
FORCEPROP 1 LAST PACK_TYPE 0805
J 0
(-2675 75);
DISPLAY 0.617021 (-2675 75);
PAINT SKYBLUE (-2675 75);
FORCEPROP 1 LAST PART_NUMBER C95333-007
J 0
(-2675 125);
DISPLAY 0.617021 (-2675 125);
PAINT BLUE (-2675 125);
FORCEPROP 1 LAST TOLERANCE 10%
J 0
(-2675 225);
DISPLAY 0.617021 (-2675 225);
PAINT SKYBLUE (-2675 225);
FORCEPROP 1 LASTPIN (-2725 375) $PN 1
J 0
(-2715 355);
DISPLAY 0.617021 (-2715 355);
PAINT ORANGE (-2715 355);
FORCEPROP 1 LAST VOLTAGE 16V
J 0
(-2675 275);
DISPLAY 0.617021 (-2675 275);
PAINT SKYBLUE (-2675 275);
FORCEPROP 1 LAST VALUE 10UF
J 0
(-2675 325);
DISPLAY 0.617021 (-2675 325);
PAINT SKYBLUE (-2675 325);
FORCEPROP 1 LAST LOCATION C9L14
J 0
(-2675 375);
DISPLAY 0.617021 (-2675 375);
PAINT AQUA (-2675 375);
FORCEPROP 2 LAST CDS_LIB mstr_discrete
J 0
(-2725 275);
PAINT ORANGE (-2725 275);
DISPLAY INVISIBLE (-2725 275);
FORCEPROP 2 LAST CDS_LOCATION C9L14
J 0
(-2675 375);
DISPLAY 0.617021 (-2675 375);
PAINT AQUA (-2675 375);
DISPLAY INVISIBLE (-2675 375);
FORCEPROP 1 LAST PATH I84
J 0
(-2675 425);
DISPLAY 1.319149 (-2675 425);
PAINT WHITE (-2675 425);
DISPLAY INVISIBLE (-2675 425);
FORCEPROP 2 LAST ROOM VDDQ_KLM_PWR_VR
J 0
(-2675 425);
DISPLAY 1.361702 (-2675 425);
PAINT ORANGE (-2675 425);
DISPLAY INVISIBLE (-2675 425);
FORCEPROP 2 LAST SEC_TYPE 0805
J 0
(-2675 500);
DISPLAY 1.021277 (-2675 500);
PAINT ORANGE (-2675 500);
DISPLAY INVISIBLE (-2675 500);
FORCEPROP 2 LAST SEC 1
J 0
(-2675 500);
DISPLAY 0.680851 (-2675 500);
PAINT MONO (-2675 500);
DISPLAY INVISIBLE (-2675 500);
FORCEADD GND..1
(-2725 -175);
FORCEPROP 3 LASTPIN (-2725 -125) SIG_NAME GND\g
J 0
(-2715 -115);
DISPLAY 0.659574 (-2715 -115);
PAINT MONO (-2715 -115);
DISPLAY INVISIBLE (-2715 -115);
FORCEPROP 2 LAST ROOM VDDQ_KLM_PWR_VR
J 0
(-3275 -100);
DISPLAY 1.936170 (-3275 -100);
PAINT ORANGE (-3275 -100);
DISPLAY INVISIBLE (-3275 -100);
FORCEPROP 2 LAST BOM_COST VDDQ_KLM_PWR_VR
J 0
(-3100 -100);
DISPLAY 1.446809 (-3100 -100);
PAINT MONO (-3100 -100);
DISPLAY INVISIBLE (-3100 -100);
FORCEPROP 1 LAST VOLTAGE 0
J 0
(-2725 -175);
PAINT SKYBLUE (-2725 -175);
DISPLAY INVISIBLE (-2725 -175);
FORCEPROP 2 LAST CDS_LIB mstr_symbols
J 0
(-2725 -175);
PAINT ORANGE (-2725 -175);
DISPLAY INVISIBLE (-2725 -175);
FORCEPROP 1 LAST PATH I85
J 0
(-2650 -175);
DISPLAY 1.170213 (-2650 -175);
PAINT AQUA (-2650 -175);
DISPLAY INVISIBLE (-2650 -175);
FORCEPROP 1 LAST SIZE 1B
J 0
(-2650 -225);
DISPLAY 1.723404 (-2650 -225);
PAINT GREEN (-2650 -225);
DISPLAY INVISIBLE (-2650 -225);
FORCEPROP 1 LAST BODY_TYPE PLUMBING
J 0
(-2770 -218);
DISPLAY 0.340426 (-2770 -218);
PAINT GREEN (-2770 -218);
DISPLAY INVISIBLE (-2770 -218);
FORCEPROP 1 LAST HDL_POWER GND
J 0
(-2725 -25);
DISPLAY 1.723404 (-2725 -25);
PAINT GREEN (-2725 -25);
DISPLAY INVISIBLE (-2725 -25);
FORCEADD VCC_CORE..1
(-2650 2775);
FORCEPROP 3 LASTPIN (-2650 2725) SIG_NAME VR_FET_SW_P12V_STBY_PVDDQ_KLM\g
J 0
(-2640 2735);
DISPLAY 0.659574 (-2640 2735);
PAINT MONO (-2640 2735);
DISPLAY INVISIBLE (-2640 2735);
FORCEPROP 1 LAST HDL_POWER VR_FET_SW_P12V_STBY_PVDDQ_KLM
J 1
(-2575 2825);
DISPLAY 0.617021 (-2575 2825);
PAINT GREEN (-2575 2825);
FORCEPROP 2 LAST CDS_LIB mstr_symbols
J 0
(-2650 2775);
PAINT ORANGE (-2650 2775);
DISPLAY INVISIBLE (-2650 2775);
FORCEPROP 1 LAST PATH I86
J 0
(-2600 2800);
DISPLAY 1.170213 (-2600 2800);
PAINT AQUA (-2600 2800);
DISPLAY INVISIBLE (-2600 2800);
FORCEADD P5V_STBY..1
(200 950);
FORCEPROP 3 LASTPIN (200 900) SIG_NAME P5V_STBY\g
J 0
(210 910);
DISPLAY 0.659574 (210 910);
PAINT MONO (210 910);
DISPLAY INVISIBLE (210 910);
FORCEPROP 1 LAST VOLTAGE 5.0V
J 0
(155 907);
DISPLAY 0.340426 (155 907);
PAINT SKYBLUE (155 907);
DISPLAY INVISIBLE (155 907);
FORCEPROP 2 LAST CDS_LIB mstr_symbols
J 0
(200 950);
PAINT ORANGE (200 950);
DISPLAY INVISIBLE (200 950);
FORCEPROP 1 LAST SIZE 1B
J 0
(245 972);
DISPLAY 0.340426 (245 972);
PAINT GREEN (245 972);
DISPLAY INVISIBLE (245 972);
FORCEPROP 1 LAST PATH I88
J 0
(245 952);
DISPLAY 0.340426 (245 952);
PAINT GREEN (245 952);
DISPLAY INVISIBLE (245 952);
FORCEPROP 1 LAST BODY_TYPE PLUMBING
J 0
(155 907);
DISPLAY 0.340426 (155 907);
PAINT GREEN (155 907);
DISPLAY INVISIBLE (155 907);
FORCEPROP 1 LAST HDL_POWER P5V_STBY
J 0
(-100 825);
DISPLAY 0.872340 (-100 825);
PAINT ORANGE (-100 825);
DISPLAY INVISIBLE (-100 825);
FORCEADD DNS..2
(4330 2320);
PAINT RED (4330 2320);
FORCEPROP 2 LAST CDS_LIB mstr_misc
J 0
(4330 2320);
PAINT ORANGE (4330 2320);
DISPLAY INVISIBLE (4330 2320);
FORCEPROP 1 LAST COMMENT_BODY TRUE
R 1
J 0
(4405 2095);
DISPLAY 0.872340 (4405 2095);
PAINT GREEN (4405 2095);
DISPLAY INVISIBLE (4405 2095);
FORCEADD DNS..2
(4305 170);
PAINT RED (4305 170);
FORCEPROP 2 LAST CDS_LIB mstr_misc
J 0
(4305 170);
PAINT ORANGE (4305 170);
DISPLAY INVISIBLE (4305 170);
FORCEPROP 1 LAST COMMENT_BODY TRUE
R 1
J 0
(4380 -55);
DISPLAY 0.872340 (4380 -55);
PAINT GREEN (4380 -55);
DISPLAY INVISIBLE (4380 -55);
FORCEADD INTEL_CORP_BPAGE..1
(4925 -1575);
FORCEPROP 1 LAST CDS_CON_LAST_MODIFIED Tue Dec 01 11:52:28 2015
J 0
(3500 -1250);
DISPLAY 1.936170 (3500 -1250);
PAINT GREEN (3500 -1250);
DISPLAY INVISIBLE (3500 -1250);
FORCEPROP 1 LAST CUSTOM_TXT_CDS <CURRENT_DESIGN_SHEET> OF <TOTAL_DESIGN_SHEETS>
J 0
(4425 -1550);
PAINT GREEN (4425 -1550);
FORCEPROP 2 LAST CUSTOM_TXT_CDS <XR_PAGE_TITLE>
J 0
(-2965 3675);
DISPLAY 0.638298 (-2965 3675);
PAINT PINK (-2965 3675);
DISPLAY INVISIBLE (-2965 3675);
FORCEPROP 2 LAST CUSTOM_TXT_CDS <CON_LAST_MODIFIED>
J 0
(3000 -1250);
PAINT ORANGE (3000 -1250);
FORCEPROP 1 LAST SCH_DEPT BESD
J 1
(475 -1475);
DISPLAY 1.212766 (475 -1475);
PAINT YELLOW (475 -1475);
FORCEPROP 1 LAST SCH_ADDRESS1 2200 Mission College Blvd.
J 0
(950 -1450);
DISPLAY 0.617021 (950 -1450);
PAINT GREEN (950 -1450);
FORCEPROP 1 LAST SCH_ADDRESS2 P.O. BOX 58119
J 0
(950 -1500);
DISPLAY 0.617021 (950 -1500);
PAINT GREEN (950 -1500);
FORCEPROP 1 LAST SCH_ADDRESS3 Santa Clara, CA 95052-8119
J 0
(950 -1550);
DISPLAY 0.617021 (950 -1550);
PAINT GREEN (950 -1550);
FORCEPROP 1 LAST SCH_REV 2.420
J 0
(4675 -1425);
DISPLAY 0.978723 (4675 -1425);
PAINT YELLOW (4675 -1425);
FORCEPROP 1 LAST SCH_NUMBER H4694802
J 0
(3625 -1425);
DISPLAY 1.212766 (3625 -1425);
PAINT YELLOW (3625 -1425);
FORCEPROP 1 LAST SCH_TITLE VDDQ KLM VR (2 OF 3)
J 0
(-3025 -1525);
DISPLAY 1.212766 (-3025 -1525);
PAINT ORANGE (-3025 -1525);
FORCEPROP 2 LAST CDS_LIB mstr_symbols
J 0
(4925 -1575);
DISPLAY 1.936170 (4925 -1575);
PAINT ORANGE (4925 -1575);
DISPLAY INVISIBLE (4925 -1575);
FORCEPROP 2 LAST PAGE_BORDER TRUE
J 0
(-2965 3675);
DISPLAY 1.255319 (-2965 3675);
PAINT PINK (-2965 3675);
DISPLAY INVISIBLE (-2965 3675);
FORCEPROP 2 LAST ROOM VDDQ_KLM_PWR_VR
J 0
(-3175 3525);
DISPLAY 1.936170 (-3175 3525);
PAINT ORANGE (-3175 3525);
DISPLAY INVISIBLE (-3175 3525);
FORCEPROP 1 LAST COMMENT_BODY TRUE
J 0
(4937 -1563);
DISPLAY 0.893617 (4937 -1563);
PAINT GREEN (4937 -1563);
DISPLAY INVISIBLE (4937 -1563);
FORCEPROP 2 LAST CDS_XR_PAGE_TITLE CR-227 : @BASEBOARD_FAB2_LIB.BASEBOARD_FAB2(SCH_1):PAGE227
J 0
(-2965 3675);
DISPLAY 0.638298 (-2965 3675);
PAINT PINK (-2965 3675);
DISPLAY INVISIBLE (-2965 3675);
WIRE 16 -1 (1000 2300)(900 2300);
WIRE 16 -1 (900 2300)(900 1100);
WIRE 16 -1 (900 1100)(3400 1100);
WIRE 16 -1 (3400 1100)(3400 1850);
WIRE 16 -1 (3175 1850)(3400 1850);
WIRE 16 -1 (3400 1850)(4025 1850);
WIRE 16 -1 (4025 1750)(4025 1850);
WIRE 16 -1 (4025 1850)(4025 1900);
WIRE 16 -1 (4325 2075)(4325 2225);
WIRE 16 -1 (4300 -75)(4300 75);
WIRE 16 -1 (1000 2400)(875 2400);
WIRE 16 -1 (875 2400)(875 2500);
WIRE 16 -1 (1000 2500)(875 2500);
WIRE 16 -1 (875 2500)(275 2500);
WIRE 16 -1 (275 2500)(275 3025);
WIRE 16 -1 (275 3025)(250 3025);
WIRE 16 -1 (-575 3025)(250 3025);
WIRE 16 -1 (250 3025)(250 3075);
WIRE 16 -1 (-675 3025)(-575 3025);
WIRE 16 -1 (-575 2525)(-575 3025);
WIRE 16 -1 (-1000 3025)(-675 3025);
WIRE 16 -1 (-675 2525)(-675 3025);
WIRE 16 -1 (825 1550)(825 1450);
WIRE 16 -1 (2600 1275)(2600 1200);
WIRE 16 -1 (2725 2025)(2725 1975);
WIRE 16 -1 (2575 -875)(2575 -925);
WIRE 16 -1 (2600 -50)(2600 -100);
WIRE 16 -1 (800 -600)(800 -700);
WIRE 16 -1 (2000 1750)(2350 1750);
WIRE 16 -1 (2350 1700)(2350 1750);
WIRE 16 -1 (2350 1650)(2350 1700);
WIRE 16 -1 (2350 1700)(2000 1700);
WIRE 16 -1 (2350 1600)(2350 1650);
WIRE 16 -1 (2350 1650)(2000 1650);
WIRE 16 -1 (2350 1450)(2350 1600);
WIRE 16 -1 (2350 1600)(2000 1600);
WIRE 16 -1 (-575 2325)(-575 2125);
WIRE 16 -1 (-575 2125)(-675 2125);
WIRE 16 -1 (-675 2325)(-675 2125);
WIRE 16 -1 (-1350 2125)(-675 2125);
WIRE 16 -1 (-1350 2325)(-1350 2125);
WIRE 16 -1 (-1350 2125)(-1675 2125);
WIRE 16 -1 (-1675 2275)(-1675 2125);
WIRE 16 -1 (-1675 2125)(-1900 2125);
WIRE 16 -1 (-1900 2325)(-1900 2125);
WIRE 16 -1 (-1900 2125)(-2175 2125);
WIRE 16 -1 (-2175 2325)(-2175 2125);
WIRE 16 -1 (-2175 2125)(-2400 2125);
WIRE 16 -1 (-2400 2300)(-2400 2125);
WIRE 16 -1 (-2400 2125)(-2650 2125);
WIRE 16 -1 (-2650 2350)(-2650 2125);
WIRE 16 -1 (-2650 2050)(-2650 2125);
WIRE 16 -1 (975 150)(850 150);
WIRE 16 -1 (850 150)(850 -1025);
WIRE 16 -1 (850 -1025)(3525 -1025);
WIRE 16 -1 (3525 -1025)(3525 -300);
WIRE 16 -1 (3250 -300)(3525 -300);
WIRE 16 -1 (4025 -300)(3525 -300);
WIRE 16 -1 (4025 -400)(4025 -300);
WIRE 16 -1 (4025 -300)(4025 -250);
WIRE 16 -1 (4025 -675)(4025 -600);
WIRE 16 -1 (4025 1475)(4025 1550);
WIRE 16 -1 (1975 -400)(2350 -400);
WIRE 16 -1 (2350 -450)(2350 -400);
WIRE 16 -1 (2350 -500)(2350 -450);
WIRE 16 -1 (2350 -450)(1975 -450);
WIRE 16 -1 (2350 -550)(2350 -500);
WIRE 16 -1 (2350 -500)(1975 -500);
WIRE 16 -1 (2350 -700)(2350 -550);
WIRE 16 -1 (2350 -550)(1975 -550);
WIRE 16 -1 (750 500)(975 500);
WIRE 16 -1 (750 500)(750 450);
WIRE 16 -1 (975 450)(750 450);
WIRE 16 -1 (750 450)(-1750 450);
WIRE 16 -1 (-1750 375)(-1750 450);
WIRE 16 -1 (-1750 450)(-1975 450);
WIRE 16 -1 (-1975 375)(-1975 450);
WIRE 16 -1 (-1975 450)(-2225 450);
WIRE 16 -1 (-2225 375)(-2225 450);
WIRE 16 -1 (-2225 450)(-2475 450);
WIRE 16 -1 (-2475 325)(-2475 450);
WIRE 16 -1 (-2475 450)(-2725 450);
WIRE 16 -1 (-2725 375)(-2725 450);
WIRE 16 -1 (-2725 700)(-2725 450);
WIRE 16 -1 (-650 175)(-650 -50);
WIRE 16 -1 (-650 -50)(-750 -50);
WIRE 16 -1 (-750 175)(-750 -50);
WIRE 16 -1 (-750 -50)(-1275 -50);
WIRE 16 -1 (-1275 200)(-1275 -50);
WIRE 16 -1 (-1275 -50)(-1750 -50);
WIRE 16 -1 (-1750 175)(-1750 -50);
WIRE 16 -1 (-1750 -50)(-1975 -50);
WIRE 16 -1 (-1975 175)(-1975 -50);
WIRE 16 -1 (-1975 -50)(-2225 -50);
WIRE 16 -1 (-2225 175)(-2225 -50);
WIRE 16 -1 (-2475 -50)(-2225 -50);
WIRE 16 -1 (-2475 125)(-2475 -50);
WIRE 16 -1 (-2475 -50)(-2725 -50);
WIRE 16 -1 (-2725 175)(-2725 -50);
WIRE 16 -1 (-2725 -125)(-2725 -50);
WIRE 16 -1 (1000 2650)(750 2650);
WIRE 16 -1 (750 2650)(750 2600);
WIRE 16 -1 (1000 2600)(750 2600);
WIRE 16 -1 (750 2600)(-1675 2600);
WIRE 16 -1 (-1675 2475)(-1675 2600);
WIRE 16 -1 (-1675 2600)(-1900 2600);
WIRE 16 -1 (-1900 2525)(-1900 2600);
WIRE 16 -1 (-1900 2600)(-2175 2600);
WIRE 16 -1 (-2175 2525)(-2175 2600);
WIRE 16 -1 (-2175 2600)(-2400 2600);
WIRE 16 -1 (-2400 2500)(-2400 2600);
WIRE 16 -1 (-2400 2600)(-2650 2600);
WIRE 16 -1 (-2650 2550)(-2650 2600);
WIRE 16 -1 (-2650 2725)(-2650 2600);
WIRE 16 -1 (975 250)(875 250);
WIRE 16 -1 (875 250)(875 350);
WIRE 16 -1 (875 350)(975 350);
WIRE 16 -1 (200 350)(875 350);
WIRE 16 -1 (200 825)(200 350);
WIRE 16 -1 (200 825)(-650 825);
WIRE 16 -1 (200 825)(200 900);
WIRE 16 -1 (-650 825)(-750 825);
WIRE 16 -1 (-650 375)(-650 825);
WIRE 16 -1 (-750 825)(-950 825);
WIRE 16 -1 (-750 375)(-750 825);
WIRE 3 2175 (2500 -1000)(2900 -1000);
WIRE 3 2175 (2500 -250)(2500 -1000);
WIRE 3 2175 (2900 -250)(2900 -1000);
WIRE 3 2175 (2500 -250)(2900 -250);
WIRE 16 -1 (1975 -300)(2575 -300);
FORCEPROP 2 LAST SIG_NAME VR_PVDDQ_KLM_PH2_SW
J 0
(2060 -290);
DISPLAY 0.617021 (2060 -290);
PAINT ORANGE (2060 -290);
FORCEPROP 2 LASTPROP $XRERR UNIQUE?
J 0
(1820 -290);
DISPLAY 0.638298 (1820 -290);
PAINT MONO (1820 -290);
DISPLAY INVISIBLE (1820 -290);
WIRE 16 -1 (2575 -300)(3050 -300);
WIRE 16 -1 (2575 -350)(2575 -300);
WIRE 3 2175 (2325 175)(2850 175);
WIRE 3 2175 (2325 175)(2325 -200);
WIRE 3 2175 (2850 175)(2850 -200);
WIRE 3 2175 (2325 -200)(2850 -200);
WIRE 16 -1 (-1275 550)(975 550);
FORCEPROP 2 LAST SIG_NAME VR_PVDDQ_KLM_PH2_VCIN
J 0
(-1240 585);
DISPLAY 0.617021 (-1240 585);
PAINT ORANGE (-1240 585);
FORCEPROP 2 LASTPROP $XRERR UNIQUE?
J 0
(-1480 585);
DISPLAY 0.638298 (-1480 585);
PAINT MONO (-1480 585);
DISPLAY INVISIBLE (-1480 585);
WIRE 16 -1 (-1275 550)(-1275 825);
WIRE 16 -1 (-1275 400)(-1275 550);
WIRE 16 -1 (-1275 825)(-1150 825);
WIRE 3 2175 (525 1325)(1075 1325);
WIRE 3 2175 (525 1925)(525 1325);
WIRE 3 2175 (1075 1925)(1075 1325);
WIRE 3 2175 (525 1925)(1075 1925);
WIRE 3 2175 (-425 1775)(175 1775);
WIRE 3 2175 (-425 2025)(-425 1775);
WIRE 3 2175 (175 2025)(175 1775);
WIRE 3 2175 (-425 2025)(175 2025);
WIRE 16 2175 (-1225 -150)(-400 -150);
WIRE 16 2175 (-1225 -150)(-1225 -550);
WIRE 16 2175 (-400 -150)(-400 -550);
WIRE 16 2175 (-1225 -550)(-400 -550);
WIRE 3 2175 (-350 -125)(50 -125);
WIRE 3 2175 (-350 -125)(-350 -400);
WIRE 3 2175 (50 -125)(50 -400);
WIRE 3 2175 (-350 -400)(50 -400);
WIRE 16 -1 (-1625 -100)(975 -100);
FORCEPROP 2 LAST SIG_NAME VR_PVDDQ_KLM_PWM2
J 0
(-1638 -90);
DISPLAY 0.617021 (-1638 -90);
PAINT ORANGE (-1638 -90);
WIRE 16 -1 (-950 1700)(700 1700);
FORCEPROP 2 LAST SIG_NAME VR_PVDDQ_KLM_PH1_PHASE
J 0
(-865 1710);
DISPLAY 0.617021 (-865 1710);
PAINT ORANGE (-865 1710);
FORCEPROP 2 LASTPROP $XRERR UNIQUE?
J 0
(-1105 1710);
DISPLAY 0.638298 (-1105 1710);
PAINT MONO (-1105 1710);
DISPLAY INVISIBLE (-1105 1710);
WIRE 16 -1 (-950 1700)(-950 1750);
WIRE 16 -1 (700 1700)(700 1800);
WIRE 16 -1 (700 1800)(1000 1800);
WIRE 16 -1 (1975 300)(2650 300);
FORCEPROP 2 LAST SIG_NAME NC_PVDDQ_KLM_PH2_P31
J 0
(2112 310);
DISPLAY 0.617021 (2112 310);
PAINT ORANGE (2112 310);
FORCEPROP 2 LASTPROP $XRERR UNIQUE?
J 0
(2680 300);
DISPLAY 0.638298 (2680 300);
PAINT MONO (2680 300);
DISPLAY INVISIBLE (2680 300);
WIRE 16 -1 (-100 -225)(700 -225);
FORCEPROP 2 LAST SIG_NAME VR_PVDDQ_KLM_PH2_BOOT_R
J 0
(235 -215);
DISPLAY 0.617021 (235 -215);
PAINT ORANGE (235 -215);
FORCEPROP 2 LASTPROP $XRERR UNIQUE?
J 0
(-5 -215);
DISPLAY 0.638298 (-5 -215);
PAINT MONO (-5 -215);
DISPLAY INVISIBLE (-5 -215);
WIRE 16 -1 (700 -225)(700 -300);
WIRE 16 -1 (700 -300)(975 -300);
WIRE 16 -1 (-950 -450)(700 -450);
FORCEPROP 2 LAST SIG_NAME VR_PVDDQ_KLM_PH2_PHASE
J 0
(-915 -440);
DISPLAY 0.617021 (-915 -440);
PAINT ORANGE (-915 -440);
FORCEPROP 2 LASTPROP $XRERR UNIQUE?
J 0
(-1155 -440);
DISPLAY 0.638298 (-1155 -440);
PAINT MONO (-1155 -440);
DISPLAY INVISIBLE (-1155 -440);
WIRE 16 -1 (-950 -450)(-950 -425);
WIRE 16 -1 (700 -450)(700 -350);
WIRE 16 -1 (700 -350)(975 -350);
WIRE 3 2175 (550 -250)(1050 -250);
WIRE 3 2175 (550 -250)(550 -800);
WIRE 3 2175 (1050 -250)(1050 -800);
WIRE 3 2175 (550 -800)(1050 -800);
WIRE 16 2175 (-1025 425)(-225 425);
WIRE 16 2175 (-1025 425)(-1025 -25);
WIRE 16 2175 (-225 425)(-225 -25);
WIRE 16 2175 (-1025 -25)(-225 -25);
WIRE 16 2175 (-1300 1600)(-775 1600);
WIRE 16 2175 (-1300 2000)(-1300 1600);
WIRE 16 2175 (-775 2000)(-775 1600);
WIRE 16 2175 (-1300 2000)(-775 2000);
WIRE 16 -1 (1975 350)(4300 350);
FORCEPROP 0 LAST VOLTAGE 3.6
J 0
(2050 425);
DISPLAY 1.021277 (2050 425);
PAINT SKYBLUE (2050 425);
DISPLAY INVISIBLE (2050 425);
FORCEPROP 2 LAST SIG_NAME VR_PVDDQ_KLM_PH2_OCSET
J 0
(2107 366);
DISPLAY 0.617021 (2107 366);
PAINT ORANGE (2107 366);
FORCEPROP 2 LASTPROP $XRERR UNIQUE?
J 0
(1867 366);
DISPLAY 0.638298 (1867 366);
PAINT MONO (1867 366);
DISPLAY INVISIBLE (1867 366);
WIRE 16 -1 (4300 275)(4300 350);
WIRE 16 -1 (1975 200)(2600 200);
FORCEPROP 2 LAST SIG_NAME A_TSENSE_PVDDQ_KLM
J 0
(2237 210);
DISPLAY 0.617021 (2237 210);
PAINT ORANGE (2237 210);
WIRE 16 -1 (1975 200)(1975 50);
WIRE 16 -1 (2600 200)(3075 200);
WIRE 16 -1 (2600 150)(2600 200);
WIRE 16 -1 (800 900)(3575 900);
FORCEPROP 2 LAST SIG_NAME VR_PVDDQ_KLM_AIREF2
J 0
(2722 901);
DISPLAY 0.617021 (2722 901);
PAINT ORANGE (2722 901);
WIRE 16 -1 (800 -200)(800 900);
WIRE 16 -1 (975 -200)(800 -200);
WIRE 16 -1 (800 -400)(800 -200);
WIRE 16 -1 (0 50)(975 50);
FORCEPROP 0 LAST SIG_NAME TP_PVDDQ_KLM_PH2_GL_1
J 0
(27 65);
DISPLAY 0.617021 (27 65);
PAINT ORANGE (27 65);
FORCEPROP 2 LASTPROP $XRERR UNIQUE?
J 0
(-240 50);
DISPLAY 0.638298 (-240 50);
PAINT MONO (-240 50);
DISPLAY INVISIBLE (-240 50);
WIRE 16 -1 (0 0)(975 0);
FORCEPROP 0 LAST SIG_NAME TP_PVDDQ_KLM_PH2_GL_0
J 0
(27 15);
DISPLAY 0.617021 (27 15);
PAINT ORANGE (27 15);
FORCEPROP 2 LASTPROP $XRERR UNIQUE?
J 0
(-240 0);
DISPLAY 0.638298 (-240 0);
PAINT MONO (-240 0);
DISPLAY INVISIBLE (-240 0);
WIRE 16 -1 (-950 -225)(-300 -225);
FORCEPROP 2 LAST SIG_NAME VR_PVDDQ_KLM_PH2_BOOT
J 0
(-915 -215);
DISPLAY 0.617021 (-915 -215);
PAINT ORANGE (-915 -215);
FORCEPROP 2 LASTPROP $XRERR UNIQUE?
J 0
(-1155 -215);
DISPLAY 0.638298 (-1155 -215);
PAINT MONO (-1155 -215);
DISPLAY INVISIBLE (-1155 -215);
WIRE 16 -1 (25 1950)(700 1950);
FORCEPROP 2 LAST SIG_NAME VR_PVDDQ_KLM_PH1_BOOT_R
J 0
(210 1960);
DISPLAY 0.617021 (210 1960);
PAINT ORANGE (210 1960);
FORCEPROP 2 LASTPROP $XRERR UNIQUE?
J 0
(-30 1960);
DISPLAY 0.638298 (-30 1960);
PAINT MONO (-30 1960);
DISPLAY INVISIBLE (-30 1960);
WIRE 16 -1 (700 1950)(700 1850);
WIRE 16 -1 (700 1850)(1000 1850);
WIRE 3 2175 (2425 1825)(2950 1825);
WIRE 3 2175 (2425 1825)(2425 1125);
WIRE 3 2175 (2950 1825)(2950 1125);
WIRE 3 2175 (2425 1125)(2950 1125);
WIRE 3 2175 (2625 2375)(3150 2375);
WIRE 3 2175 (2625 2375)(2625 1900);
WIRE 3 2175 (3150 2375)(3150 1900);
WIRE 3 2175 (2625 1900)(3150 1900);
WIRE 16 -1 (2000 2275)(2725 2275);
FORCEPROP 2 LAST SIG_NAME A_TSENSE_PVDDQ_KLM
J 0
(2087 2285);
DISPLAY 0.617021 (2087 2285);
PAINT ORANGE (2087 2285);
WIRE 16 -1 (2000 2275)(2000 2200);
WIRE 16 -1 (2725 2275)(3250 2275);
WIRE 16 -1 (2725 2225)(2725 2275);
WIRE 16 -1 (2000 2500)(4325 2500);
FORCEPROP 0 LAST VOLTAGE 3.6
J 0
(2075 2575);
DISPLAY 1.021277 (2075 2575);
PAINT SKYBLUE (2075 2575);
DISPLAY INVISIBLE (2075 2575);
FORCEPROP 2 LAST SIG_NAME VR_PVDDQ_KLM_PH1_OCSET
J 0
(2132 2516);
DISPLAY 0.617021 (2132 2516);
PAINT ORANGE (2132 2516);
FORCEPROP 2 LASTPROP $XRERR UNIQUE?
J 0
(1892 2516);
DISPLAY 0.638298 (1892 2516);
PAINT MONO (1892 2516);
DISPLAY INVISIBLE (1892 2516);
WIRE 16 -1 (4325 2425)(4325 2500);
WIRE 16 -1 (-950 1950)(-175 1950);
FORCEPROP 2 LAST SIG_NAME VR_PVDDQ_KLM_PH1_BOOT
J 0
(-915 1960);
DISPLAY 0.617021 (-915 1960);
PAINT ORANGE (-915 1960);
FORCEPROP 2 LASTPROP $XRERR UNIQUE?
J 0
(-1155 1960);
DISPLAY 0.638298 (-1155 1960);
PAINT MONO (-1155 1960);
DISPLAY INVISIBLE (-1155 1960);
WIRE 16 -1 (-1750 2050)(1000 2050);
WIRE 16 -1 (2600 1625)(2600 1525);
WIRE 16 -1 (2000 1850)(2600 1850);
FORCEPROP 2 LAST SIG_NAME VR_PVDDQ_KLM_PH1_SW
J 0
(2110 1860);
DISPLAY 0.617021 (2110 1860);
PAINT ORANGE (2110 1860);
FORCEPROP 2 LASTPROP $XRERR UNIQUE?
J 0
(1870 1860);
DISPLAY 0.638298 (1870 1860);
PAINT MONO (1870 1860);
DISPLAY INVISIBLE (1870 1860);
WIRE 16 -1 (2600 1850)(2975 1850);
WIRE 16 -1 (2600 1775)(2600 1850);
WIRE 16 -1 (3150 3025)(825 3025);
FORCEPROP 2 LAST SIG_NAME VR_PVDDQ_KLM_AIREF1
J 0
(2484 3032);
DISPLAY 0.617021 (2484 3032);
PAINT ORANGE (2484 3032);
WIRE 16 -1 (825 1950)(825 3025);
WIRE 16 -1 (1000 1950)(825 1950);
WIRE 16 -1 (825 1750)(825 1950);
WIRE 16 -1 (1975 550)(3550 550);
FORCEPROP 2 LAST SIG_NAME ISENSE_PVDDQ_KLM_PH2_IMON
J 0
(2537 560);
DISPLAY 0.617021 (2537 560);
PAINT ORANGE (2537 560);
WIRE 16 -1 (1000 2700)(-1350 2700);
FORCEPROP 2 LAST SIG_NAME VR_PVDDQ_KLM_PH1_VCIN
J 0
(-1340 2710);
DISPLAY 0.617021 (-1340 2710);
PAINT ORANGE (-1340 2710);
FORCEPROP 2 LASTPROP $XRERR UNIQUE?
J 0
(-1580 2710);
DISPLAY 0.638298 (-1580 2710);
PAINT MONO (-1580 2710);
DISPLAY INVISIBLE (-1580 2710);
WIRE 16 -1 (-1350 2700)(-1350 3025);
WIRE 16 -1 (-1350 2525)(-1350 2700);
WIRE 16 -1 (-1350 3025)(-1200 3025);
WIRE 16 -1 (100 2200)(1000 2200);
FORCEPROP 0 LAST SIG_NAME TP_PVDDQ_KLM_PH1_GL_1
J 0
(177 2215);
DISPLAY 0.617021 (177 2215);
PAINT ORANGE (177 2215);
FORCEPROP 2 LASTPROP $XRERR UNIQUE?
J 0
(-140 2200);
DISPLAY 0.638298 (-140 2200);
PAINT MONO (-140 2200);
DISPLAY INVISIBLE (-140 2200);
WIRE 16 -1 (2575 -500)(2575 -625);
WIRE 16 -1 (2000 2450)(2675 2450);
FORCEPROP 2 LAST SIG_NAME NC_PVDDQ_KLM_PH1_P31
J 0
(2137 2460);
DISPLAY 0.617021 (2137 2460);
PAINT ORANGE (2137 2460);
FORCEPROP 2 LASTPROP $XRERR UNIQUE?
J 0
(2705 2450);
DISPLAY 0.638298 (2705 2450);
PAINT MONO (2705 2450);
DISPLAY INVISIBLE (2705 2450);
WIRE 16 -1 (100 2150)(1000 2150);
FORCEPROP 0 LAST SIG_NAME TP_PVDDQ_KLM_PH1_GL_0
J 0
(177 2165);
DISPLAY 0.617021 (177 2165);
PAINT ORANGE (177 2165);
FORCEPROP 2 LASTPROP $XRERR UNIQUE?
J 0
(-140 2150);
DISPLAY 0.638298 (-140 2150);
PAINT MONO (-140 2150);
DISPLAY INVISIBLE (-140 2150);
WIRE 16 -1 (2000 2700)(3175 2700);
FORCEPROP 2 LAST SIG_NAME ISENSE_PVDDQ_KLM_PH1_IMON
J 0
(2312 2710);
DISPLAY 0.617021 (2312 2710);
PAINT ORANGE (2312 2710);
WIRE 16 2175 (-950 2150)(-225 2150);
WIRE 16 2175 (-950 2575)(-950 2150);
WIRE 16 2175 (-225 2575)(-225 2150);
WIRE 16 2175 (-950 2575)(-225 2575);
DOT 1 (-650 825);
DOT 1 (800 -200);
DOT 1 (2600 200);
DOT 1 (2575 -300);
DOT 1 (-2725 -50);
DOT 1 (-2475 -50);
DOT 1 (-2225 -50);
DOT 1 (-1975 -50);
DOT 1 (-1750 -50);
DOT 1 (-1275 -50);
DOT 1 (-750 -50);
DOT 1 (-2725 450);
DOT 1 (-2475 450);
DOT 1 (-2225 450);
DOT 1 (-1975 450);
DOT 1 (-1750 450);
DOT 1 (2350 -500);
DOT 1 (4025 -300);
DOT 1 (200 825);
DOT 1 (-2650 2125);
DOT 1 (-2650 2600);
DOT 1 (-2400 2125);
DOT 1 (-2175 2125);
DOT 1 (-2400 2600);
DOT 1 (-2175 2600);
DOT 1 (-1900 2125);
DOT 1 (-1675 2125);
DOT 1 (-1900 2600);
DOT 1 (-1675 2600);
DOT 1 (-1350 2125);
DOT 1 (-675 2125);
DOT 1 (-675 3025);
DOT 1 (-575 3025);
DOT 1 (250 3025);
DOT 1 (875 2500);
DOT 1 (750 2600);
DOT 1 (2350 1650);
DOT 1 (2350 1700);
DOT 1 (4025 1850);
DOT 1 (3525 -300);
DOT 1 (2350 -550);
DOT 1 (750 450);
DOT 1 (2350 1600);
DOT 1 (875 350);
DOT 1 (825 1950);
DOT 1 (2600 1850);
DOT 1 (2725 2275);
DOT 1 (-1275 550);
DOT 1 (-750 825);
DOT 1 (3400 1850);
DOT 1 (2350 -450);
DOT 1 (-1350 2700);
FORCENOTE
SPOF
(-1230 -650) 0;
DISPLAY LEFT (-1230 -650);
DISPLAY 1.808511 (-1230 -650);
PAINT PURPLE (-1230 -650);
FORCENOTE
PLACE ON TOP
(-1030 0) 0;
DISPLAY LEFT (-1030 0);
DISPLAY 1.553191 (-1030 0);
PAINT PURPLE (-1030 0);
FORCENOTE
ROOM = VDDQ_KLM_PWR_VR
(-3005 -1400) 0;
DISPLAY LEFT (-3005 -1400);
DISPLAY 2.319149 (-3005 -1400);
PAINT PURPLE (-3005 -1400);
FORCENOTE
PLACE ON TOP
(-955 2150) 0;
DISPLAY LEFT (-955 2150);
DISPLAY 1.553191 (-955 2150);
PAINT PURPLE (-955 2150);
FORCENOTE
TP FAB1 CO-LAY WITH TI PARTS 11/16
(3150 2100) 0;
DISPLAY LEFT (3150 2100);
DISPLAY 0.851064 (3150 2100);
PAINT RED (3150 2100);
FORCENOTE
SPOF
(-1355 1525) 0;
DISPLAY LEFT (-1355 1525);
DISPLAY 1.936170 (-1355 1525);
PAINT PURPLE (-1355 1525);
FORCENOTE
TP FAB1 CO-LAY WITH TI PARTS 11/16
(-650 1400) 0;
DISPLAY LEFT (-650 1400);
DISPLAY 0.851064 (-650 1400);
PAINT RED (-650 1400);
FORCENOTE
TP FAB1 CO-LAYOUT WITH TI PARTS 11/16
(-525 -725) 0;
DISPLAY LEFT (-525 -725);
DISPLAY 0.851064 (-525 -725);
PAINT RED (-525 -725);
FORCENOTE
TP FAB1 3.01 OHM NEED CHANGE TO 2.2 OHM BUT WAIT FOR SYMBOL
(1700 -1175) 0;
DISPLAY LEFT (1700 -1175);
DISPLAY 0.851064 (1700 -1175);
PAINT RED (1700 -1175);
FORCENOTE
TP FAB1 CO-LAY WITH TI PARTS 11/16
(2875 -25) 0;
DISPLAY LEFT (2875 -25);
DISPLAY 0.851064 (2875 -25);
PAINT RED (2875 -25);
FORCENOTE
TP FAB1 CO-LAY WITH TI PARTS 11/16
(2250 -1100) 0;
DISPLAY LEFT (2250 -1100);
DISPLAY 0.851064 (2250 -1100);
PAINT RED (2250 -1100);
FORCENOTE
TP FAB1 3.01 OHM NEED CHANGE TO 2.2 OHM BUT WAIT FOR SYMBOL
(2375 1025) 0;
DISPLAY LEFT (2375 1025);
DISPLAY 0.851064 (2375 1025);
PAINT RED (2375 1025);
FORCENOTE
TP FAB1 CO-LAY WITH TI PARTS 11/16
(2975 1400) 0;
DISPLAY LEFT (2975 1400);
DISPLAY 0.851064 (2975 1400);
PAINT RED (2975 1400);
QUIT
